FILE_TYPE = MACRO_DRAWING;
SET COLOR_WIRE YELLOW;
SET COLOR_PROP ORANGE;
SET COLOR_DOT WHITE;
SET COLOR_ARC YELLOW;
SET COLOR_BODY GREEN;
SET COLOR_NOTE PURPLE;
SET PROP_DISPLAY VALUE;
SET PAGE_NUMBER P361;
FORCEADD Q_RES..2
(1800 1375);
FORCEPROP 1 LAST LOCATION R60
J 0
(1845 1500);
DISPLAY 0.978723 (1845 1500);
FORCEPROP 2 LAST $SEC 1
J 0
(1850 1600);
DISPLAY 0.680851 (1850 1600);
PAINT MONO (1850 1600);
DISPLAY INVISIBLE (1850 1600);
FORCEPROP 2 LAST CDS_SEC 1
J 0
(1850 1600);
DISPLAY 1.021277 (1850 1600);
DISPLAY INVISIBLE (1850 1600);
FORCEPROP 1 LASTPIN (1800 1475) $PN 1
J 0
(1805 1437);
DISPLAY 0.787234 (1805 1437);
FORCEPROP 1 LASTPIN (1800 1275) $PN 2
J 0
(1805 1285);
DISPLAY 0.787234 (1805 1285);
FORCEPROP 1 LAST VALUE 10K
J 0
(1845 1450);
DISPLAY 0.638298 (1845 1450);
FORCEPROP 1 LAST TOLERANCE 1%
J 0
(1845 1400);
DISPLAY 0.638298 (1845 1400);
FORCEPROP 1 LAST WATTAGE 1/16W
J 0
(1840 1350);
DISPLAY 0.638298 (1840 1350);
FORCEPROP 1 LAST MATERIAL EMPTY
J 0
(1840 1300);
DISPLAY 0.638298 (1840 1300);
PAINT RED (1840 1300);
FORCEPROP 1 LAST PACK_TYPE 0402LF
J 0
(1840 1250);
DISPLAY 0.638298 (1840 1250);
FORCEPROP 2 LAST CDS_LIB pure_quanta
J 0
(1800 1375);
PAINT MONO (1800 1375);
DISPLAY INVISIBLE (1800 1375);
FORCEPROP 1 LAST PATH I101
J 0
(1850 1550);
DISPLAY 0.978723 (1850 1550);
PAINT WHITE (1850 1550);
DISPLAY INVISIBLE (1850 1550);
FORCEPROP 1 LAST PART_NUMBER CS31002FB08
J 0
(1840 1250);
DISPLAY 0.510638 (1840 1250);
DISPLAY INVISIBLE (1840 1250);
FORCEADD UNIVERSAL_POWER..1
(1525 1750);
FORCEPROP 3 LASTPIN (1525 1700) SIG_NAME P3V3_AUX\g
J 0
(1535 1710);
DISPLAY 0.659574 (1535 1710);
PAINT MONO (1535 1710);
DISPLAY INVISIBLE (1535 1710);
FORCEPROP 1 LAST HDL_POWER P3V3_AUX
J 1
(1525 1800);
DISPLAY 0.872340 (1525 1800);
PAINT GREEN (1525 1800);
FORCEPROP 2 LAST CDS_LIB pure_quanta_power
J 0
(1525 1750);
PAINT MONO (1525 1750);
DISPLAY INVISIBLE (1525 1750);
FORCEPROP 1 LAST PATH I102
J 0
(1575 1775);
DISPLAY 0.872340 (1575 1775);
PAINT AQUA (1575 1775);
DISPLAY INVISIBLE (1575 1775);
FORCEADD Q_RES..2
(1525 1375);
FORCEPROP 1 LAST LOCATION R52
J 0
(1570 1500);
DISPLAY 0.978723 (1570 1500);
FORCEPROP 2 LAST $SEC 1
J 0
(1575 1600);
DISPLAY 0.680851 (1575 1600);
PAINT MONO (1575 1600);
DISPLAY INVISIBLE (1575 1600);
FORCEPROP 2 LAST CDS_SEC 1
J 0
(1575 1600);
DISPLAY 1.021277 (1575 1600);
DISPLAY INVISIBLE (1575 1600);
FORCEPROP 1 LASTPIN (1525 1475) $PN 1
J 0
(1530 1437);
DISPLAY 0.787234 (1530 1437);
FORCEPROP 1 LASTPIN (1525 1275) $PN 2
J 0
(1530 1285);
DISPLAY 0.787234 (1530 1285);
FORCEPROP 1 LAST WATTAGE 1/16W
J 0
(1565 1350);
DISPLAY 0.638298 (1565 1350);
FORCEPROP 1 LAST MATERIAL EMPTY
J 0
(1565 1300);
DISPLAY 0.638298 (1565 1300);
PAINT RED (1565 1300);
FORCEPROP 1 LAST PACK_TYPE 0402LF
J 0
(1565 1250);
DISPLAY 0.638298 (1565 1250);
FORCEPROP 1 LAST TOLERANCE 1%
J 0
(1570 1400);
DISPLAY 0.638298 (1570 1400);
FORCEPROP 1 LAST VALUE 10K
J 0
(1570 1450);
DISPLAY 0.638298 (1570 1450);
FORCEPROP 2 LAST CDS_LIB pure_quanta
J 0
(1525 1375);
PAINT MONO (1525 1375);
DISPLAY INVISIBLE (1525 1375);
FORCEPROP 1 LAST PATH I103
J 0
(1575 1550);
DISPLAY 0.978723 (1575 1550);
PAINT WHITE (1575 1550);
DISPLAY INVISIBLE (1575 1550);
FORCEPROP 1 LAST PART_NUMBER CS31002FB08
J 0
(1565 1250);
DISPLAY 0.510638 (1565 1250);
DISPLAY INVISIBLE (1565 1250);
FORCEADD Q_RES..2
(1800 825);
FORCEPROP 1 LAST LOCATION R62
J 0
(1845 950);
DISPLAY 0.978723 (1845 950);
FORCEPROP 2 LAST $SEC 1
J 0
(1850 1050);
DISPLAY 0.680851 (1850 1050);
PAINT MONO (1850 1050);
DISPLAY INVISIBLE (1850 1050);
FORCEPROP 2 LAST CDS_SEC 1
J 0
(1850 1050);
DISPLAY 1.021277 (1850 1050);
DISPLAY INVISIBLE (1850 1050);
FORCEPROP 1 LASTPIN (1800 925) $PN 1
J 0
(1805 887);
DISPLAY 0.787234 (1805 887);
FORCEPROP 1 LASTPIN (1800 725) $PN 2
J 0
(1805 735);
DISPLAY 0.787234 (1805 735);
FORCEPROP 1 LAST VALUE 1K
J 0
(1845 900);
DISPLAY 0.638298 (1845 900);
FORCEPROP 1 LAST TOLERANCE 1%
J 0
(1845 850);
DISPLAY 0.638298 (1845 850);
FORCEPROP 1 LAST MATERIAL CHIP
J 0
(1840 750);
DISPLAY 0.638298 (1840 750);
FORCEPROP 1 LAST PACK_TYPE 0402LF
J 0
(1840 700);
DISPLAY 0.638298 (1840 700);
FORCEPROP 1 LAST WATTAGE 1/16W
J 0
(1840 800);
DISPLAY 0.638298 (1840 800);
FORCEPROP 2 LAST CDS_LIB pure_quanta
J 0
(1800 825);
PAINT MONO (1800 825);
DISPLAY INVISIBLE (1800 825);
FORCEPROP 1 LAST PATH I104
J 0
(1850 1000);
DISPLAY 0.978723 (1850 1000);
PAINT WHITE (1850 1000);
DISPLAY INVISIBLE (1850 1000);
FORCEPROP 1 LAST PART_NUMBER CS21002FB06
J 0
(1840 700);
DISPLAY 0.510638 (1840 700);
DISPLAY INVISIBLE (1840 700);
FORCEADD UNIVERSAL_GND..1
(1800 600);
FORCEPROP 3 LASTPIN (1800 650) SIG_NAME GND\g
J 0
(1810 660);
DISPLAY 0.659574 (1810 660);
PAINT MONO (1810 660);
DISPLAY INVISIBLE (1810 660);
FORCEPROP 2 LAST ROOM IO_SLOT
J 1
(1575 675);
DISPLAY 0.744681 (1575 675);
DISPLAY INVISIBLE (1575 675);
FORCEPROP 2 LAST CDS_LIB pure_quanta_power
J 0
(1800 600);
PAINT MONO (1800 600);
DISPLAY INVISIBLE (1800 600);
FORCEPROP 1 LAST HDL_POWER GND
J 1
(1825 525);
DISPLAY 0.872340 (1825 525);
PAINT GREEN (1825 525);
DISPLAY INVISIBLE (1825 525);
FORCEPROP 1 LAST PATH I105
J 0
(1875 600);
DISPLAY 0.872340 (1875 600);
PAINT AQUA (1875 600);
DISPLAY INVISIBLE (1875 600);
FORCEADD UNIVERSAL_GND..1
(1525 600);
FORCEPROP 3 LASTPIN (1525 650) SIG_NAME GND\g
J 0
(1535 660);
DISPLAY 0.659574 (1535 660);
PAINT MONO (1535 660);
DISPLAY INVISIBLE (1535 660);
FORCEPROP 2 LAST ROOM IO_SLOT
J 1
(1300 675);
DISPLAY 0.744681 (1300 675);
DISPLAY INVISIBLE (1300 675);
FORCEPROP 2 LAST CDS_LIB pure_quanta_power
J 0
(1525 600);
PAINT MONO (1525 600);
DISPLAY INVISIBLE (1525 600);
FORCEPROP 1 LAST HDL_POWER GND
J 1
(1550 525);
DISPLAY 0.872340 (1550 525);
PAINT GREEN (1550 525);
DISPLAY INVISIBLE (1550 525);
FORCEPROP 1 LAST PATH I106
J 0
(1600 600);
DISPLAY 0.872340 (1600 600);
PAINT AQUA (1600 600);
DISPLAY INVISIBLE (1600 600);
FORCEADD Q_RES..2
(1525 825);
FORCEPROP 1 LAST LOCATION R54
J 0
(1570 950);
DISPLAY 0.978723 (1570 950);
FORCEPROP 2 LAST $SEC 1
J 0
(1575 1050);
DISPLAY 0.680851 (1575 1050);
PAINT MONO (1575 1050);
DISPLAY INVISIBLE (1575 1050);
FORCEPROP 2 LAST CDS_SEC 1
J 0
(1575 1050);
DISPLAY 1.021277 (1575 1050);
DISPLAY INVISIBLE (1575 1050);
FORCEPROP 1 LASTPIN (1525 925) $PN 1
J 0
(1530 887);
DISPLAY 0.787234 (1530 887);
FORCEPROP 1 LASTPIN (1525 725) $PN 2
J 0
(1530 735);
DISPLAY 0.787234 (1530 735);
FORCEPROP 1 LAST VALUE 1K
J 0
(1570 900);
DISPLAY 0.638298 (1570 900);
FORCEPROP 1 LAST MATERIAL CHIP
J 0
(1565 750);
DISPLAY 0.638298 (1565 750);
FORCEPROP 1 LAST WATTAGE 1/16W
J 0
(1565 800);
DISPLAY 0.638298 (1565 800);
FORCEPROP 1 LAST PACK_TYPE 0402LF
J 0
(1565 700);
DISPLAY 0.638298 (1565 700);
FORCEPROP 1 LAST TOLERANCE 1%
J 0
(1570 850);
DISPLAY 0.638298 (1570 850);
FORCEPROP 2 LAST CDS_LIB pure_quanta
J 0
(1525 825);
PAINT MONO (1525 825);
DISPLAY INVISIBLE (1525 825);
FORCEPROP 1 LAST PATH I107
J 0
(1575 1000);
DISPLAY 0.978723 (1575 1000);
PAINT WHITE (1575 1000);
DISPLAY INVISIBLE (1575 1000);
FORCEPROP 1 LAST PART_NUMBER CS21002FB06
J 0
(1565 700);
DISPLAY 0.510638 (1565 700);
DISPLAY INVISIBLE (1565 700);
FORCEADD UNIVERSAL_GND..1
(225 750);
FORCEPROP 3 LASTPIN (225 800) SIG_NAME GND\g
J 0
(235 810);
DISPLAY 0.659574 (235 810);
PAINT MONO (235 810);
DISPLAY INVISIBLE (235 810);
FORCEPROP 2 LAST CDS_LIB pure_quanta_power
J 0
(225 750);
PAINT MONO (225 750);
DISPLAY INVISIBLE (225 750);
FORCEPROP 1 LAST HDL_POWER GND
J 1
(250 675);
DISPLAY 0.872340 (250 675);
PAINT GREEN (250 675);
DISPLAY INVISIBLE (250 675);
FORCEPROP 1 LAST PATH I108
J 0
(300 750);
DISPLAY 0.872340 (300 750);
PAINT AQUA (300 750);
DISPLAY INVISIBLE (300 750);
FORCEADD UNIVERSAL_POWER..1
(-750 1725);
FORCEPROP 3 LASTPIN (-750 1675) SIG_NAME P3V3_AUX\g
J 0
(-740 1685);
DISPLAY 0.659574 (-740 1685);
PAINT MONO (-740 1685);
DISPLAY INVISIBLE (-740 1685);
FORCEPROP 1 LAST HDL_POWER P3V3_AUX
J 1
(-750 1775);
DISPLAY 0.872340 (-750 1775);
PAINT GREEN (-750 1775);
FORCEPROP 2 LAST CDS_LIB pure_quanta_power
J 0
(-750 1725);
PAINT MONO (-750 1725);
DISPLAY INVISIBLE (-750 1725);
FORCEPROP 1 LAST PATH I109
J 0
(-700 1750);
DISPLAY 0.872340 (-700 1750);
PAINT AQUA (-700 1750);
DISPLAY INVISIBLE (-700 1750);
FORCEADD Q_CAP..1
R 2
(-750 1400);
FORCEPROP 1 LAST LOCATION C1
J 2
(-800 1500);
DISPLAY 0.978723 (-800 1500);
FORCEPROP 2 LAST $SEC 1
J 0
(-800 1600);
DISPLAY 0.680851 (-800 1600);
PAINT MONO (-800 1600);
DISPLAY INVISIBLE (-800 1600);
FORCEPROP 2 LAST CDS_SEC 1
J 0
(-800 1600);
DISPLAY 1.021277 (-800 1600);
DISPLAY INVISIBLE (-800 1600);
FORCEPROP 1 LASTPIN (-750 1500) $PN 1
J 2
(-760 1480);
DISPLAY 0.787234 (-760 1480);
FORCEPROP 1 LASTPIN (-750 1300) $PN 2
J 2
(-760 1280);
DISPLAY 0.787234 (-760 1280);
FORCEPROP 1 LAST TOLERANCE 10%
J 2
(-800 1350);
DISPLAY 0.510638 (-800 1350);
FORCEPROP 1 LAST MATERIAL X7R
J 2
(-800 1300);
DISPLAY 0.510638 (-800 1300);
FORCEPROP 1 LAST VOLTAGE 25V
J 2
(-800 1400);
DISPLAY 0.510638 (-800 1400);
FORCEPROP 1 LAST VALUE 0.1UF
J 2
(-800 1450);
DISPLAY 0.510638 (-800 1450);
FORCEPROP 1 LAST PACK_TYPE 0402
J 2
(-800 1200);
DISPLAY 0.510638 (-800 1200);
FORCEPROP 2 LAST CDS_LIB pure_quanta
J 0
(-750 1400);
PAINT MONO (-750 1400);
DISPLAY INVISIBLE (-750 1400);
FORCEPROP 1 LAST PATH I110
J 2
(-800 1550);
DISPLAY 0.978723 (-800 1550);
PAINT WHITE (-800 1550);
DISPLAY INVISIBLE (-800 1550);
FORCEPROP 1 LAST PART_NUMBER CH4104K1B00
J 2
(-800 1250);
DISPLAY 0.510638 (-800 1250);
DISPLAY INVISIBLE (-800 1250);
FORCEADD UNIVERSAL_GND..1
(-750 1175);
FORCEPROP 3 LASTPIN (-750 1225) SIG_NAME GND\g
J 0
(-740 1235);
DISPLAY 0.659574 (-740 1235);
PAINT MONO (-740 1235);
DISPLAY INVISIBLE (-740 1235);
FORCEPROP 2 LAST CDS_LIB pure_quanta_power
J 0
(-750 1175);
PAINT MONO (-750 1175);
DISPLAY INVISIBLE (-750 1175);
FORCEPROP 1 LAST HDL_POWER GND
J 1
(-725 1100);
DISPLAY 0.872340 (-725 1100);
PAINT GREEN (-725 1100);
DISPLAY INVISIBLE (-725 1100);
FORCEPROP 1 LAST PATH I111
J 0
(-675 1175);
DISPLAY 0.872340 (-675 1175);
PAINT AQUA (-675 1175);
DISPLAY INVISIBLE (-675 1175);
FORCEADD UNIVERSAL_POWER..1
(-2000 1650);
FORCEPROP 3 LASTPIN (-2000 1600) SIG_NAME P3V3_AUX\g
J 0
(-1990 1610);
DISPLAY 0.659574 (-1990 1610);
PAINT MONO (-1990 1610);
DISPLAY INVISIBLE (-1990 1610);
FORCEPROP 1 LAST HDL_POWER P3V3_AUX
J 1
(-2000 1700);
DISPLAY 0.872340 (-2000 1700);
PAINT GREEN (-2000 1700);
FORCEPROP 2 LAST CDS_LIB pure_quanta_power
J 0
(-2000 1650);
PAINT MONO (-2000 1650);
DISPLAY INVISIBLE (-2000 1650);
FORCEPROP 1 LAST PATH I112
J 0
(-1950 1675);
DISPLAY 0.872340 (-1950 1675);
PAINT AQUA (-1950 1675);
DISPLAY INVISIBLE (-1950 1675);
FORCEADD Q_RES..2
(-1900 1350);
FORCEPROP 1 LAST LOCATION R24
J 0
(-1855 1475);
DISPLAY 0.787234 (-1855 1475);
FORCEPROP 2 LAST $SEC 1
J 0
(-1850 1575);
DISPLAY 0.680851 (-1850 1575);
PAINT MONO (-1850 1575);
DISPLAY INVISIBLE (-1850 1575);
FORCEPROP 2 LAST CDS_SEC 1
J 0
(-1850 1575);
DISPLAY 1.021277 (-1850 1575);
DISPLAY INVISIBLE (-1850 1575);
FORCEPROP 1 LASTPIN (-1900 1450) $PN 1
J 0
(-1895 1412);
DISPLAY 0.787234 (-1895 1412);
FORCEPROP 1 LASTPIN (-1900 1250) $PN 2
J 0
(-1895 1260);
DISPLAY 0.787234 (-1895 1260);
FORCEPROP 1 LAST MATERIAL EMPTY
J 0
(-1860 1275);
DISPLAY 0.638298 (-1860 1275);
PAINT RED (-1860 1275);
FORCEPROP 1 LAST WATTAGE 1/16W
J 0
(-1860 1325);
DISPLAY 0.638298 (-1860 1325);
FORCEPROP 1 LAST TOLERANCE 5%
J 0
(-1855 1375);
DISPLAY 0.638298 (-1855 1375);
FORCEPROP 1 LAST VALUE 4.7K
J 0
(-1855 1425);
DISPLAY 0.638298 (-1855 1425);
FORCEPROP 1 LAST PACK_TYPE 0402LF
J 0
(-1860 1175);
DISPLAY 0.638298 (-1860 1175);
FORCEPROP 2 LAST CDS_LIB pure_quanta
J 0
(-1900 1350);
PAINT MONO (-1900 1350);
DISPLAY INVISIBLE (-1900 1350);
FORCEPROP 1 LAST PATH I113
J 0
(-1850 1525);
DISPLAY 0.978723 (-1850 1525);
PAINT WHITE (-1850 1525);
DISPLAY INVISIBLE (-1850 1525);
FORCEPROP 1 LAST PART_NUMBER CS24702JB10
J 0
(-1860 1225);
DISPLAY 0.638298 (-1860 1225);
DISPLAY INVISIBLE (-1860 1225);
FORCEADD Q_RES..2
R 2
(-2000 1350);
FORCEPROP 1 LAST LOCATION R4
J 2
(-2045 1475);
DISPLAY 0.787234 (-2045 1475);
FORCEPROP 2 LAST $SEC 1
J 0
(-2050 1575);
DISPLAY 0.680851 (-2050 1575);
PAINT MONO (-2050 1575);
DISPLAY INVISIBLE (-2050 1575);
FORCEPROP 2 LAST CDS_SEC 1
J 0
(-2050 1575);
DISPLAY 1.021277 (-2050 1575);
DISPLAY INVISIBLE (-2050 1575);
FORCEPROP 1 LASTPIN (-2000 1450) $PN 1
J 2
(-2005 1412);
DISPLAY 0.787234 (-2005 1412);
FORCEPROP 1 LASTPIN (-2000 1250) $PN 2
J 2
(-2005 1260);
DISPLAY 0.787234 (-2005 1260);
FORCEPROP 1 LAST VALUE 4.7K
J 2
(-2045 1425);
DISPLAY 0.638298 (-2045 1425);
FORCEPROP 1 LAST TOLERANCE 5%
J 2
(-2045 1375);
DISPLAY 0.638298 (-2045 1375);
FORCEPROP 1 LAST WATTAGE 1/16W
J 2
(-2040 1325);
DISPLAY 0.638298 (-2040 1325);
FORCEPROP 1 LAST MATERIAL EMPTY
J 2
(-2040 1275);
DISPLAY 0.638298 (-2040 1275);
PAINT RED (-2040 1275);
FORCEPROP 1 LAST PACK_TYPE 0402LF
J 2
(-2040 1175);
DISPLAY 0.638298 (-2040 1175);
FORCEPROP 2 LAST CDS_LIB pure_quanta
J 2
(-2000 1350);
PAINT MONO (-2000 1350);
DISPLAY INVISIBLE (-2000 1350);
FORCEPROP 1 LAST PATH I114
J 2
(-2050 1525);
DISPLAY 0.978723 (-2050 1525);
PAINT WHITE (-2050 1525);
DISPLAY INVISIBLE (-2050 1525);
FORCEPROP 1 LAST PART_NUMBER CS24702JB10
J 2
(-2040 1225);
DISPLAY 0.638298 (-2040 1225);
DISPLAY INVISIBLE (-2040 1225);
FORCEADD Q_RES..2
(-1075 750);
FORCEPROP 1 LAST LOCATION R44
J 0
(-1030 875);
DISPLAY 0.978723 (-1030 875);
FORCEPROP 2 LAST $SEC 1
J 0
(-1025 975);
DISPLAY 0.680851 (-1025 975);
PAINT MONO (-1025 975);
DISPLAY INVISIBLE (-1025 975);
FORCEPROP 2 LAST CDS_SEC 1
J 0
(-1025 975);
DISPLAY 1.021277 (-1025 975);
DISPLAY INVISIBLE (-1025 975);
FORCEPROP 1 LASTPIN (-1075 850) $PN 1
J 0
(-1070 812);
DISPLAY 0.787234 (-1070 812);
FORCEPROP 1 LASTPIN (-1075 650) $PN 2
J 0
(-1070 660);
DISPLAY 0.787234 (-1070 660);
FORCEPROP 1 LAST VALUE 1K
J 0
(-1030 825);
DISPLAY 0.510638 (-1030 825);
FORCEPROP 1 LAST PACK_TYPE 0402LF
J 0
(-1035 575);
DISPLAY 0.510638 (-1035 575);
FORCEPROP 1 LAST MATERIAL CHIP
J 0
(-1035 675);
DISPLAY 0.510638 (-1035 675);
FORCEPROP 1 LAST WATTAGE 1/16W
J 0
(-1035 725);
DISPLAY 0.510638 (-1035 725);
FORCEPROP 1 LAST TOLERANCE 1%
J 0
(-1030 775);
DISPLAY 0.510638 (-1030 775);
FORCEPROP 2 LAST CDS_LIB pure_quanta
J 0
(-1075 750);
PAINT MONO (-1075 750);
DISPLAY INVISIBLE (-1075 750);
FORCEPROP 1 LAST PATH I115
J 0
(-1025 925);
DISPLAY 0.978723 (-1025 925);
PAINT WHITE (-1025 925);
DISPLAY INVISIBLE (-1025 925);
FORCEPROP 1 LAST PART_NUMBER CS21002FB06
J 0
(-1035 625);
DISPLAY 0.510638 (-1035 625);
DISPLAY INVISIBLE (-1035 625);
FORCEADD UNIVERSAL_GND..1
(-1075 525);
FORCEPROP 3 LASTPIN (-1075 575) SIG_NAME GND\g
J 0
(-1065 585);
DISPLAY 0.659574 (-1065 585);
PAINT MONO (-1065 585);
DISPLAY INVISIBLE (-1065 585);
FORCEPROP 2 LAST CDS_LIB pure_quanta_power
J 0
(-1075 525);
PAINT MONO (-1075 525);
DISPLAY INVISIBLE (-1075 525);
FORCEPROP 1 LAST HDL_POWER GND
J 1
(-1050 450);
DISPLAY 0.872340 (-1050 450);
PAINT GREEN (-1050 450);
DISPLAY INVISIBLE (-1050 450);
FORCEPROP 1 LAST PATH I116
J 0
(-1000 525);
DISPLAY 0.872340 (-1000 525);
PAINT AQUA (-1000 525);
DISPLAY INVISIBLE (-1000 525);
FORCEADD OFFPAGE..1
(-3150 1050);
FORCEPROP 2 LAST $XR1 239 
J 0
(-3522 1050);
DISPLAY 0.638298 (-3522 1050);
PAINT MONO (-3522 1050);
FORCEPROP 2 LAST $XR0 251 
J 0
(-3402 1050);
DISPLAY 0.638298 (-3402 1050);
PAINT MONO (-3402 1050);
FORCEPROP 2 LAST CDS_LIB standard
J 0
(-3150 1050);
PAINT MONO (-3150 1050);
DISPLAY INVISIBLE (-3150 1050);
FORCEPROP 1 LAST OFFPAGE TRUE
J 0
(-2825 925);
DISPLAY 0.872340 (-2825 925);
PAINT GREEN (-2825 925);
DISPLAY INVISIBLE (-2825 925);
FORCEPROP 1 LAST COMMENT_BODY TRUE
J 0
(-3025 950);
DISPLAY 0.872340 (-3025 950);
PAINT GREEN (-3025 950);
DISPLAY INVISIBLE (-3025 950);
FORCEPROP 2 LAST PATH I118
J 0
(-3400 1100);
DISPLAY 0.680851 (-3400 1100);
DISPLAY INVISIBLE (-3400 1100);
FORCEADD OFFPAGE..3
R 2
(-3150 1000);
FORCEPROP 2 LAST $XR1 251 
J 0
(-3550 1000);
DISPLAY 0.638298 (-3550 1000);
PAINT MONO (-3550 1000);
FORCEPROP 2 LAST $XR0 239 
J 0
(-3430 1000);
DISPLAY 0.638298 (-3430 1000);
PAINT MONO (-3430 1000);
FORCEPROP 2 LAST CDS_LIB standard
J 0
(-3150 1000);
PAINT MONO (-3150 1000);
DISPLAY INVISIBLE (-3150 1000);
FORCEPROP 1 LAST OFFPAGE TRUE
J 2
(-3475 875);
DISPLAY 0.872340 (-3475 875);
DISPLAY INVISIBLE (-3475 875);
FORCEPROP 1 LAST COMMENT_BODY TRUE
J 2
(-3100 900);
DISPLAY 0.872340 (-3100 900);
PAINT GREEN (-3100 900);
DISPLAY INVISIBLE (-3100 900);
FORCEPROP 2 LAST PATH I119
J 0
(-3425 1050);
DISPLAY 0.680851 (-3425 1050);
DISPLAY INVISIBLE (-3425 1050);
FORCEADD Q_RES..2
(2075 1375);
FORCEPROP 1 LAST LOCATION R68
J 0
(2120 1500);
DISPLAY 0.978723 (2120 1500);
FORCEPROP 2 LAST $SEC 1
J 0
(2125 1600);
DISPLAY 0.680851 (2125 1600);
PAINT MONO (2125 1600);
DISPLAY INVISIBLE (2125 1600);
FORCEPROP 2 LAST CDS_SEC 1
J 0
(2125 1600);
DISPLAY 1.021277 (2125 1600);
DISPLAY INVISIBLE (2125 1600);
FORCEPROP 1 LASTPIN (2075 1475) $PN 1
J 0
(2080 1437);
DISPLAY 0.787234 (2080 1437);
FORCEPROP 1 LASTPIN (2075 1275) $PN 2
J 0
(2080 1285);
DISPLAY 0.787234 (2080 1285);
FORCEPROP 1 LAST VALUE 1K
J 0
(2120 1450);
DISPLAY 0.638298 (2120 1450);
FORCEPROP 1 LAST TOLERANCE 1%
J 0
(2120 1400);
DISPLAY 0.638298 (2120 1400);
FORCEPROP 1 LAST WATTAGE 1/16W
J 0
(2115 1350);
DISPLAY 0.638298 (2115 1350);
FORCEPROP 1 LAST MATERIAL EMPTY
J 0
(2115 1300);
DISPLAY 0.638298 (2115 1300);
PAINT RED (2115 1300);
FORCEPROP 1 LAST PACK_TYPE 0402LF
J 0
(2115 1250);
DISPLAY 0.638298 (2115 1250);
FORCEPROP 2 LAST CDS_LIB pure_quanta
J 0
(2075 1375);
PAINT MONO (2075 1375);
DISPLAY INVISIBLE (2075 1375);
FORCEPROP 1 LAST PATH I120
J 0
(2125 1550);
DISPLAY 0.978723 (2125 1550);
PAINT WHITE (2125 1550);
DISPLAY INVISIBLE (2125 1550);
FORCEPROP 1 LAST PART_NUMBER CS21002FB06
J 0
(2115 1200);
DISPLAY 0.638298 (2115 1200);
DISPLAY INVISIBLE (2115 1200);
FORCEADD Q_RES..2
(2075 825);
FORCEPROP 1 LAST LOCATION R69
J 0
(2120 950);
DISPLAY 0.978723 (2120 950);
FORCEPROP 2 LAST $SEC 1
J 0
(2125 1050);
DISPLAY 0.680851 (2125 1050);
PAINT MONO (2125 1050);
DISPLAY INVISIBLE (2125 1050);
FORCEPROP 2 LAST CDS_SEC 1
J 0
(2125 1050);
DISPLAY 1.021277 (2125 1050);
DISPLAY INVISIBLE (2125 1050);
FORCEPROP 1 LASTPIN (2075 925) $PN 1
J 0
(2080 887);
DISPLAY 0.787234 (2080 887);
FORCEPROP 1 LASTPIN (2075 725) $PN 2
J 0
(2080 735);
DISPLAY 0.787234 (2080 735);
FORCEPROP 1 LAST VALUE 10K
J 0
(2120 900);
DISPLAY 0.638298 (2120 900);
FORCEPROP 1 LAST MATERIAL CHIP
J 0
(2115 750);
DISPLAY 0.638298 (2115 750);
FORCEPROP 1 LAST PACK_TYPE 0402LF
J 0
(2115 700);
DISPLAY 0.638298 (2115 700);
FORCEPROP 1 LAST TOLERANCE 1%
J 0
(2120 850);
DISPLAY 0.638298 (2120 850);
FORCEPROP 1 LAST WATTAGE 1/16W
J 0
(2115 800);
DISPLAY 0.638298 (2115 800);
FORCEPROP 2 LAST CDS_LIB pure_quanta
J 0
(2075 825);
PAINT MONO (2075 825);
DISPLAY INVISIBLE (2075 825);
FORCEPROP 1 LAST PATH I121
J 0
(2125 1000);
DISPLAY 0.978723 (2125 1000);
PAINT WHITE (2125 1000);
DISPLAY INVISIBLE (2125 1000);
FORCEPROP 1 LAST PART_NUMBER CS31002FB08
J 0
(2115 650);
DISPLAY 0.638298 (2115 650);
DISPLAY INVISIBLE (2115 650);
FORCEADD Q_RES..1
(-2325 1050);
FORCEPROP 1 LAST LOCATION R121
J 0
(-2575 1050);
DISPLAY 0.808511 (-2575 1050);
FORCEPROP 0 LAST $SEC 1
J 0
(-2575 1100);
DISPLAY 0.680851 (-2575 1100);
PAINT MONO (-2575 1100);
DISPLAY INVISIBLE (-2575 1100);
FORCEPROP 0 LAST CDS_SEC 1
J 0
(-2575 1100);
DISPLAY 0.680851 (-2575 1100);
DISPLAY INVISIBLE (-2575 1100);
FORCEPROP 1 LASTPIN (-2425 1050) $PN 1
J 0
(-2413 1062);
DISPLAY 0.787234 (-2413 1062);
PAINT MONO (-2413 1062);
FORCEPROP 1 LASTPIN (-2225 1050) $PN 2
J 0
(-2263 1062);
DISPLAY 0.787234 (-2263 1062);
PAINT MONO (-2263 1062);
FORCEPROP 1 LAST VALUE 0
J 2
(-2175 1050);
DISPLAY 0.404255 (-2175 1050);
FORCEPROP 1 LAST MATERIAL CHIP
J 0
(-2100 1050);
DISPLAY 0.404255 (-2100 1050);
FORCEPROP 1 LAST TOLERANCE 5%
J 0
(-2150 1050);
DISPLAY 0.404255 (-2150 1050);
FORCEPROP 2 LAST CDS_LIB pure_quanta
J 0
(-2325 1050);
DISPLAY INVISIBLE (-2325 1050);
FORCEPROP 1 LAST WATTAGE 1/16W
J 2
(-2350 900);
DISPLAY 0.978723 (-2350 900);
DISPLAY INVISIBLE (-2350 900);
FORCEPROP 1 LAST PACK_TYPE 0402LF
J 0
(-2075 1050);
DISPLAY 0.638298 (-2075 1050);
DISPLAY INVISIBLE (-2075 1050);
FORCEPROP 1 LAST PATH I122
J 0
(-2375 1200);
DISPLAY 0.978723 (-2375 1200);
PAINT WHITE (-2375 1200);
DISPLAY INVISIBLE (-2375 1200);
FORCEPROP 1 LAST PART_NUMBER CS00002JB13
J 0
(-2450 900);
DISPLAY 0.510638 (-2450 900);
DISPLAY INVISIBLE (-2450 900);
FORCEADD Q_RES..1
(-2325 1000);
FORCEPROP 1 LAST LOCATION R125
J 0
(-2575 1000);
DISPLAY 0.787234 (-2575 1000);
FORCEPROP 0 LAST $SEC 1
J 0
(-2575 1050);
DISPLAY 0.680851 (-2575 1050);
PAINT MONO (-2575 1050);
DISPLAY INVISIBLE (-2575 1050);
FORCEPROP 0 LAST CDS_SEC 1
J 0
(-2575 1050);
DISPLAY 0.680851 (-2575 1050);
DISPLAY INVISIBLE (-2575 1050);
FORCEPROP 1 LASTPIN (-2425 1000) $PN 1
J 0
(-2413 1012);
DISPLAY 0.787234 (-2413 1012);
PAINT MONO (-2413 1012);
FORCEPROP 1 LASTPIN (-2225 1000) $PN 2
J 0
(-2263 1012);
DISPLAY 0.787234 (-2263 1012);
PAINT MONO (-2263 1012);
FORCEPROP 1 LAST TOLERANCE 5%
J 0
(-2150 1000);
DISPLAY 0.404255 (-2150 1000);
FORCEPROP 1 LAST MATERIAL CHIP
J 0
(-2100 1000);
DISPLAY 0.404255 (-2100 1000);
FORCEPROP 1 LAST VALUE 0
J 2
(-2175 1000);
DISPLAY 0.404255 (-2175 1000);
FORCEPROP 1 LAST PACK_TYPE 0402LF
J 0
(-2075 1000);
DISPLAY 0.638298 (-2075 1000);
DISPLAY INVISIBLE (-2075 1000);
FORCEPROP 1 LAST WATTAGE 1/16W
J 2
(-2350 850);
DISPLAY 0.978723 (-2350 850);
DISPLAY INVISIBLE (-2350 850);
FORCEPROP 2 LAST CDS_LIB pure_quanta
J 0
(-2325 1000);
DISPLAY INVISIBLE (-2325 1000);
FORCEPROP 1 LAST PATH I123
J 0
(-2375 1150);
DISPLAY 0.978723 (-2375 1150);
PAINT WHITE (-2375 1150);
DISPLAY INVISIBLE (-2375 1150);
FORCEPROP 1 LAST PART_NUMBER CS00002JB13
J 0
(-2450 850);
DISPLAY 0.510638 (-2450 850);
DISPLAY INVISIBLE (-2450 850);
FORCEADD Q_RES..1
(-2375 3350);
FORCEPROP 1 LAST LOCATION R85
J 0
(-2525 3350);
DISPLAY 0.787234 (-2525 3350);
FORCEPROP 0 LAST $SEC 1
J 0
(-2525 3400);
DISPLAY 0.680851 (-2525 3400);
PAINT MONO (-2525 3400);
DISPLAY INVISIBLE (-2525 3400);
FORCEPROP 0 LAST CDS_SEC 1
J 0
(-2525 3400);
DISPLAY 0.680851 (-2525 3400);
DISPLAY INVISIBLE (-2525 3400);
FORCEPROP 1 LASTPIN (-2475 3350) $PN 1
J 0
(-2463 3362);
DISPLAY 0.787234 (-2463 3362);
PAINT MONO (-2463 3362);
FORCEPROP 1 LASTPIN (-2275 3350) $PN 2
J 0
(-2313 3362);
DISPLAY 0.787234 (-2313 3362);
PAINT MONO (-2313 3362);
FORCEPROP 1 LAST MATERIAL CHIP
J 0
(-2150 3350);
DISPLAY 0.404255 (-2150 3350);
FORCEPROP 1 LAST TOLERANCE 5%
J 0
(-2200 3350);
DISPLAY 0.404255 (-2200 3350);
FORCEPROP 1 LAST VALUE 0
J 2
(-2225 3350);
DISPLAY 0.404255 (-2225 3350);
FORCEPROP 1 LAST WATTAGE 1/16W
J 2
(-2400 3200);
DISPLAY 0.978723 (-2400 3200);
DISPLAY INVISIBLE (-2400 3200);
FORCEPROP 1 LAST PACK_TYPE 0402LF
J 0
(-2125 3350);
DISPLAY 0.638298 (-2125 3350);
DISPLAY INVISIBLE (-2125 3350);
FORCEPROP 2 LAST CDS_LIB pure_quanta
J 0
(-2375 3350);
DISPLAY INVISIBLE (-2375 3350);
FORCEPROP 1 LAST PATH I124
J 0
(-2425 3500);
DISPLAY 0.978723 (-2425 3500);
PAINT WHITE (-2425 3500);
DISPLAY INVISIBLE (-2425 3500);
FORCEPROP 1 LAST PART_NUMBER CS00002JB13
J 0
(-2500 3200);
DISPLAY 0.510638 (-2500 3200);
DISPLAY INVISIBLE (-2500 3200);
FORCEADD Q_RES..1
(-2375 3300);
FORCEPROP 1 LAST LOCATION R86
J 0
(-2525 3300);
DISPLAY 0.787234 (-2525 3300);
FORCEPROP 0 LAST $SEC 1
J 0
(-2525 3350);
DISPLAY 0.680851 (-2525 3350);
PAINT MONO (-2525 3350);
DISPLAY INVISIBLE (-2525 3350);
FORCEPROP 0 LAST CDS_SEC 1
J 0
(-2525 3350);
DISPLAY 0.680851 (-2525 3350);
DISPLAY INVISIBLE (-2525 3350);
FORCEPROP 1 LASTPIN (-2475 3300) $PN 1
J 0
(-2463 3312);
DISPLAY 0.787234 (-2463 3312);
PAINT MONO (-2463 3312);
FORCEPROP 1 LASTPIN (-2275 3300) $PN 2
J 0
(-2313 3312);
DISPLAY 0.787234 (-2313 3312);
PAINT MONO (-2313 3312);
FORCEPROP 1 LAST MATERIAL CHIP
J 0
(-2150 3300);
DISPLAY 0.404255 (-2150 3300);
FORCEPROP 1 LAST TOLERANCE 5%
J 0
(-2200 3300);
DISPLAY 0.404255 (-2200 3300);
FORCEPROP 1 LAST VALUE 0
J 2
(-2225 3300);
DISPLAY 0.404255 (-2225 3300);
FORCEPROP 1 LAST WATTAGE 1/16W
J 2
(-2400 3150);
DISPLAY 0.978723 (-2400 3150);
DISPLAY INVISIBLE (-2400 3150);
FORCEPROP 1 LAST PACK_TYPE 0402LF
J 0
(-2125 3300);
DISPLAY 0.638298 (-2125 3300);
DISPLAY INVISIBLE (-2125 3300);
FORCEPROP 2 LAST CDS_LIB pure_quanta
J 0
(-2375 3300);
DISPLAY INVISIBLE (-2375 3300);
FORCEPROP 1 LAST PATH I125
J 0
(-2425 3450);
DISPLAY 0.978723 (-2425 3450);
PAINT WHITE (-2425 3450);
DISPLAY INVISIBLE (-2425 3450);
FORCEPROP 1 LAST PART_NUMBER CS00002JB13
J 0
(-2500 3150);
DISPLAY 0.510638 (-2500 3150);
DISPLAY INVISIBLE (-2500 3150);
FORCEADD OFFPAGE..3
R 2
(-3350 3300);
FORCEPROP 2 LAST $XR1 251 
J 0
(-3780 3300);
DISPLAY 0.638298 (-3780 3300);
PAINT MONO (-3780 3300);
FORCEPROP 2 LAST $XR0 239 
J 0
(-3660 3300);
DISPLAY 0.638298 (-3660 3300);
PAINT MONO (-3660 3300);
FORCEPROP 2 LAST CDS_LIB standard
J 0
(-3350 3300);
PAINT MONO (-3350 3300);
DISPLAY INVISIBLE (-3350 3300);
FORCEPROP 1 LAST OFFPAGE TRUE
J 2
(-3675 3175);
DISPLAY 0.872340 (-3675 3175);
DISPLAY INVISIBLE (-3675 3175);
FORCEPROP 1 LAST COMMENT_BODY TRUE
J 2
(-3300 3200);
DISPLAY 0.872340 (-3300 3200);
PAINT GREEN (-3300 3200);
DISPLAY INVISIBLE (-3300 3200);
FORCEPROP 2 LAST PATH I126
J 0
(-3625 3350);
DISPLAY 0.680851 (-3625 3350);
DISPLAY INVISIBLE (-3625 3350);
FORCEADD OFFPAGE..1
(-3350 3350);
FORCEPROP 2 LAST $XR1 239 
J 0
(-3752 3350);
DISPLAY 0.638298 (-3752 3350);
PAINT MONO (-3752 3350);
FORCEPROP 2 LAST $XR0 251 
J 0
(-3632 3350);
DISPLAY 0.638298 (-3632 3350);
PAINT MONO (-3632 3350);
FORCEPROP 2 LAST CDS_LIB standard
J 0
(-3350 3350);
PAINT MONO (-3350 3350);
DISPLAY INVISIBLE (-3350 3350);
FORCEPROP 1 LAST OFFPAGE TRUE
J 0
(-3025 3225);
DISPLAY 0.872340 (-3025 3225);
PAINT GREEN (-3025 3225);
DISPLAY INVISIBLE (-3025 3225);
FORCEPROP 1 LAST COMMENT_BODY TRUE
J 0
(-3225 3250);
DISPLAY 0.872340 (-3225 3250);
PAINT GREEN (-3225 3250);
DISPLAY INVISIBLE (-3225 3250);
FORCEPROP 2 LAST PATH I127
J 0
(-3600 3400);
DISPLAY 0.680851 (-3600 3400);
DISPLAY INVISIBLE (-3600 3400);
FORCEADD M24128BWMN6TP..1
(-250 3375);
FORCEPROP 1 LAST LOCATION U64
J 0
(-425 3700);
DISPLAY 0.723404 (-425 3700);
PAINT GREEN (-425 3700);
FORCEPROP 0 LAST $SEC 1
J 2
(-425 3950);
DISPLAY 0.680851 (-425 3950);
PAINT MONO (-425 3950);
DISPLAY INVISIBLE (-425 3950);
FORCEPROP 2 LAST CDS_SEC 1
J 0
(-400 3750);
DISPLAY 1.021277 (-400 3750);
DISPLAY INVISIBLE (-400 3750);
FORCEPROP 0 LASTPIN (50 3450) $PN 1
J 0
(60 3460);
DISPLAY 0.680851 (60 3460);
PAINT MONO (60 3460);
FORCEPROP 0 LASTPIN (50 3400) $PN 2
J 0
(60 3410);
DISPLAY 0.680851 (60 3410);
PAINT MONO (60 3410);
FORCEPROP 0 LASTPIN (50 3350) $PN 3
J 0
(60 3360);
DISPLAY 0.680851 (60 3360);
PAINT MONO (60 3360);
FORCEPROP 0 LASTPIN (-550 3350) $PN 6
J 2
(-560 3360);
DISPLAY 0.680851 (-560 3360);
PAINT MONO (-560 3360);
FORCEPROP 0 LASTPIN (-550 3300) $PN 5
J 2
(-560 3310);
DISPLAY 0.680851 (-560 3310);
PAINT MONO (-560 3310);
FORCEPROP 0 LASTPIN (-550 3450) $PN 8
J 2
(-560 3460);
DISPLAY 0.680851 (-560 3460);
PAINT MONO (-560 3460);
FORCEPROP 0 LASTPIN (50 3300) $PN 4
J 0
(60 3310);
DISPLAY 0.680851 (60 3310);
PAINT MONO (60 3310);
FORCEPROP 0 LASTPIN (-550 3400) $PN 7
J 2
(-560 3410);
DISPLAY 0.680851 (-560 3410);
PAINT MONO (-560 3410);
FORCEPROP 2 LAST PART_TYPE SMLF
J 0
(-425 3900);
DISPLAY 0.638298 (-425 3900);
FORCEPROP 2 LAST VALUE M24128-BWMN6TP
J 0
(-425 3825);
DISPLAY 0.638298 (-425 3825);
FORCEPROP 1 LAST MATERIAL IC
J 0
(-404 3516);
DISPLAY 0.723404 (-404 3516);
PAINT GREEN (-404 3516);
FORCEPROP 2 LAST CDS_LIB pure_quanta
J 2
(-250 3375);
DISPLAY INVISIBLE (-250 3375);
FORCEPROP 1 LAST NEEDS_NO_SIZE TRUE
J 0
(-250 3375);
DISPLAY 0.723404 (-250 3375);
PAINT GREEN (-250 3375);
DISPLAY INVISIBLE (-250 3375);
FORCEPROP 1 LAST CDS_LMAN_SYM_OUTLINE -150,125,150,-125
J 0
(-250 3375);
DISPLAY 0.468085 (-250 3375);
PAINT GREEN (-250 3375);
DISPLAY INVISIBLE (-250 3375);
FORCEPROP 1 LAST PATH I35
J 0
(-250 3375);
DISPLAY 0.723404 (-250 3375);
PAINT GREEN (-250 3375);
DISPLAY INVISIBLE (-250 3375);
FORCEPROP 1 LAST PART_NUMBER AKE30Z00613
J 0
(-400 3600);
DISPLAY 0.723404 (-400 3600);
PAINT GREEN (-400 3600);
DISPLAY INVISIBLE (-400 3600);
FORCEADD Q_RES..2
(1775 3675);
FORCEPROP 1 LAST LOCATION R717
J 0
(1820 3800);
DISPLAY 0.978723 (1820 3800);
FORCEPROP 2 LAST $SEC 1
J 0
(1825 3900);
DISPLAY 0.680851 (1825 3900);
PAINT MONO (1825 3900);
DISPLAY INVISIBLE (1825 3900);
FORCEPROP 2 LAST CDS_SEC 1
J 0
(1825 3900);
DISPLAY 1.021277 (1825 3900);
DISPLAY INVISIBLE (1825 3900);
FORCEPROP 1 LASTPIN (1775 3775) $PN 1
J 0
(1780 3737);
DISPLAY 0.787234 (1780 3737);
FORCEPROP 1 LASTPIN (1775 3575) $PN 2
J 0
(1780 3585);
DISPLAY 0.787234 (1780 3585);
FORCEPROP 1 LAST TOLERANCE 1%
J 0
(1820 3700);
DISPLAY 0.638298 (1820 3700);
FORCEPROP 1 LAST VALUE 10K
J 0
(1820 3750);
DISPLAY 0.638298 (1820 3750);
FORCEPROP 1 LAST WATTAGE 1/16W
J 0
(1815 3650);
DISPLAY 0.638298 (1815 3650);
FORCEPROP 1 LAST MATERIAL EMPTY
J 0
(1815 3600);
DISPLAY 0.638298 (1815 3600);
PAINT RED (1815 3600);
FORCEPROP 1 LAST PACK_TYPE 0402LF
J 0
(1815 3550);
DISPLAY 0.638298 (1815 3550);
FORCEPROP 2 LAST CDS_LIB pure_quanta
J 0
(1775 3675);
PAINT MONO (1775 3675);
DISPLAY INVISIBLE (1775 3675);
FORCEPROP 1 LAST PATH I45
J 0
(1825 3850);
DISPLAY 0.978723 (1825 3850);
PAINT WHITE (1825 3850);
DISPLAY INVISIBLE (1825 3850);
FORCEPROP 1 LAST PART_NUMBER CS31002FB08
J 0
(1815 3550);
DISPLAY 0.510638 (1815 3550);
DISPLAY INVISIBLE (1815 3550);
FORCEADD Q_RES..2
(1500 3675);
FORCEPROP 1 LAST LOCATION R713
J 0
(1545 3800);
DISPLAY 0.978723 (1545 3800);
FORCEPROP 2 LAST $SEC 1
J 0
(1550 3900);
DISPLAY 0.680851 (1550 3900);
PAINT MONO (1550 3900);
DISPLAY INVISIBLE (1550 3900);
FORCEPROP 2 LAST CDS_SEC 1
J 0
(1550 3900);
DISPLAY 1.021277 (1550 3900);
DISPLAY INVISIBLE (1550 3900);
FORCEPROP 1 LASTPIN (1500 3775) $PN 1
J 0
(1505 3737);
DISPLAY 0.787234 (1505 3737);
FORCEPROP 1 LASTPIN (1500 3575) $PN 2
J 0
(1505 3585);
DISPLAY 0.787234 (1505 3585);
FORCEPROP 1 LAST MATERIAL EMPTY
J 0
(1540 3600);
DISPLAY 0.638298 (1540 3600);
PAINT RED (1540 3600);
FORCEPROP 1 LAST TOLERANCE 1%
J 0
(1545 3700);
DISPLAY 0.638298 (1545 3700);
FORCEPROP 1 LAST VALUE 10K
J 0
(1545 3750);
DISPLAY 0.638298 (1545 3750);
FORCEPROP 1 LAST PACK_TYPE 0402LF
J 0
(1540 3550);
DISPLAY 0.638298 (1540 3550);
FORCEPROP 1 LAST WATTAGE 1/16W
J 0
(1540 3650);
DISPLAY 0.638298 (1540 3650);
FORCEPROP 2 LAST CDS_LIB pure_quanta
J 0
(1500 3675);
PAINT MONO (1500 3675);
DISPLAY INVISIBLE (1500 3675);
FORCEPROP 1 LAST PATH I47
J 0
(1550 3850);
DISPLAY 0.978723 (1550 3850);
PAINT WHITE (1550 3850);
DISPLAY INVISIBLE (1550 3850);
FORCEPROP 1 LAST PART_NUMBER CS31002FB08
J 0
(1540 3550);
DISPLAY 0.510638 (1540 3550);
DISPLAY INVISIBLE (1540 3550);
FORCEADD UNIVERSAL_GND..1
(2050 2900);
FORCEPROP 3 LASTPIN (2050 2950) SIG_NAME GND\g
J 0
(2060 2960);
DISPLAY 0.659574 (2060 2960);
PAINT MONO (2060 2960);
DISPLAY INVISIBLE (2060 2960);
FORCEPROP 2 LAST CDS_LIB pure_quanta_power
J 0
(2050 2900);
PAINT MONO (2050 2900);
DISPLAY INVISIBLE (2050 2900);
FORCEPROP 2 LAST ROOM IO_SLOT
J 1
(1825 2975);
DISPLAY 0.744681 (1825 2975);
DISPLAY INVISIBLE (1825 2975);
FORCEPROP 1 LAST HDL_POWER GND
J 1
(2075 2825);
DISPLAY 0.872340 (2075 2825);
PAINT GREEN (2075 2825);
DISPLAY INVISIBLE (2075 2825);
FORCEPROP 1 LAST PATH I49
J 0
(2125 2900);
DISPLAY 0.872340 (2125 2900);
PAINT AQUA (2125 2900);
DISPLAY INVISIBLE (2125 2900);
FORCEADD Q_RES..2
(1775 3125);
FORCEPROP 1 LAST LOCATION R718
J 0
(1820 3250);
DISPLAY 0.978723 (1820 3250);
FORCEPROP 2 LAST $SEC 1
J 0
(1825 3350);
DISPLAY 0.680851 (1825 3350);
PAINT MONO (1825 3350);
DISPLAY INVISIBLE (1825 3350);
FORCEPROP 2 LAST CDS_SEC 1
J 0
(1825 3350);
DISPLAY 1.021277 (1825 3350);
DISPLAY INVISIBLE (1825 3350);
FORCEPROP 1 LASTPIN (1775 3225) $PN 1
J 0
(1780 3187);
DISPLAY 0.787234 (1780 3187);
FORCEPROP 1 LASTPIN (1775 3025) $PN 2
J 0
(1780 3035);
DISPLAY 0.787234 (1780 3035);
FORCEPROP 1 LAST PACK_TYPE 0402LF
J 0
(1815 3000);
DISPLAY 0.638298 (1815 3000);
FORCEPROP 1 LAST TOLERANCE 1%
J 0
(1820 3150);
DISPLAY 0.638298 (1820 3150);
FORCEPROP 1 LAST MATERIAL CHIP
J 0
(1815 3050);
DISPLAY 0.638298 (1815 3050);
FORCEPROP 1 LAST WATTAGE 1/16W
J 0
(1815 3100);
DISPLAY 0.638298 (1815 3100);
FORCEPROP 1 LAST VALUE 1K
J 0
(1820 3200);
DISPLAY 0.638298 (1820 3200);
FORCEPROP 2 LAST CDS_LIB pure_quanta
J 0
(1775 3125);
PAINT MONO (1775 3125);
DISPLAY INVISIBLE (1775 3125);
FORCEPROP 1 LAST PATH I50
J 0
(1825 3300);
DISPLAY 0.978723 (1825 3300);
PAINT WHITE (1825 3300);
DISPLAY INVISIBLE (1825 3300);
FORCEPROP 1 LAST PART_NUMBER CS21002FB06
J 0
(1815 3000);
DISPLAY 0.510638 (1815 3000);
DISPLAY INVISIBLE (1815 3000);
FORCEADD UNIVERSAL_GND..1
(1775 2900);
FORCEPROP 3 LASTPIN (1775 2950) SIG_NAME GND\g
J 0
(1785 2960);
DISPLAY 0.659574 (1785 2960);
PAINT MONO (1785 2960);
DISPLAY INVISIBLE (1785 2960);
FORCEPROP 2 LAST CDS_LIB pure_quanta_power
J 0
(1775 2900);
PAINT MONO (1775 2900);
DISPLAY INVISIBLE (1775 2900);
FORCEPROP 2 LAST ROOM IO_SLOT
J 1
(1550 2975);
DISPLAY 0.744681 (1550 2975);
DISPLAY INVISIBLE (1550 2975);
FORCEPROP 1 LAST HDL_POWER GND
J 1
(1800 2825);
DISPLAY 0.872340 (1800 2825);
PAINT GREEN (1800 2825);
DISPLAY INVISIBLE (1800 2825);
FORCEPROP 1 LAST PATH I51
J 0
(1850 2900);
DISPLAY 0.872340 (1850 2900);
PAINT AQUA (1850 2900);
DISPLAY INVISIBLE (1850 2900);
FORCEADD Q_RES..2
(1500 3125);
FORCEPROP 1 LAST LOCATION R714
J 0
(1545 3250);
DISPLAY 0.978723 (1545 3250);
FORCEPROP 2 LAST $SEC 1
J 0
(1550 3350);
DISPLAY 0.680851 (1550 3350);
PAINT MONO (1550 3350);
DISPLAY INVISIBLE (1550 3350);
FORCEPROP 2 LAST CDS_SEC 1
J 0
(1550 3350);
DISPLAY 1.021277 (1550 3350);
DISPLAY INVISIBLE (1550 3350);
FORCEPROP 1 LASTPIN (1500 3225) $PN 1
J 0
(1505 3187);
DISPLAY 0.787234 (1505 3187);
FORCEPROP 1 LASTPIN (1500 3025) $PN 2
J 0
(1505 3035);
DISPLAY 0.787234 (1505 3035);
FORCEPROP 1 LAST WATTAGE 1/16W
J 0
(1540 3100);
DISPLAY 0.638298 (1540 3100);
FORCEPROP 1 LAST VALUE 1K
J 0
(1545 3200);
DISPLAY 0.638298 (1545 3200);
FORCEPROP 1 LAST TOLERANCE 1%
J 0
(1545 3150);
DISPLAY 0.638298 (1545 3150);
FORCEPROP 1 LAST MATERIAL CHIP
J 0
(1540 3050);
DISPLAY 0.638298 (1540 3050);
FORCEPROP 1 LAST PACK_TYPE 0402LF
J 0
(1540 3000);
DISPLAY 0.638298 (1540 3000);
FORCEPROP 2 LAST CDS_LIB pure_quanta
J 0
(1500 3125);
PAINT MONO (1500 3125);
DISPLAY INVISIBLE (1500 3125);
FORCEPROP 1 LAST PATH I52
J 0
(1550 3300);
DISPLAY 0.978723 (1550 3300);
PAINT WHITE (1550 3300);
DISPLAY INVISIBLE (1550 3300);
FORCEPROP 1 LAST PART_NUMBER CS21002FB06
J 0
(1540 3000);
DISPLAY 0.510638 (1540 3000);
DISPLAY INVISIBLE (1540 3000);
FORCEADD UNIVERSAL_GND..1
(1500 2900);
FORCEPROP 3 LASTPIN (1500 2950) SIG_NAME GND\g
J 0
(1510 2960);
DISPLAY 0.659574 (1510 2960);
PAINT MONO (1510 2960);
DISPLAY INVISIBLE (1510 2960);
FORCEPROP 2 LAST CDS_LIB pure_quanta_power
J 0
(1500 2900);
PAINT MONO (1500 2900);
DISPLAY INVISIBLE (1500 2900);
FORCEPROP 2 LAST ROOM IO_SLOT
J 1
(1275 2975);
DISPLAY 0.744681 (1275 2975);
DISPLAY INVISIBLE (1275 2975);
FORCEPROP 1 LAST HDL_POWER GND
J 1
(1525 2825);
DISPLAY 0.872340 (1525 2825);
PAINT GREEN (1525 2825);
DISPLAY INVISIBLE (1525 2825);
FORCEPROP 1 LAST PATH I53
J 0
(1575 2900);
DISPLAY 0.872340 (1575 2900);
PAINT AQUA (1575 2900);
DISPLAY INVISIBLE (1575 2900);
FORCEADD UNIVERSAL_POWER..1
(-775 4025);
FORCEPROP 3 LASTPIN (-775 3975) SIG_NAME P3V3_AUX\g
J 0
(-765 3985);
DISPLAY 0.659574 (-765 3985);
PAINT MONO (-765 3985);
DISPLAY INVISIBLE (-765 3985);
FORCEPROP 1 LAST HDL_POWER P3V3_AUX
J 1
(-775 4075);
DISPLAY 0.872340 (-775 4075);
PAINT GREEN (-775 4075);
FORCEPROP 2 LAST CDS_LIB pure_quanta_power
J 0
(-775 4025);
PAINT MONO (-775 4025);
DISPLAY INVISIBLE (-775 4025);
FORCEPROP 1 LAST PATH I54
J 0
(-725 4050);
DISPLAY 0.872340 (-725 4050);
PAINT AQUA (-725 4050);
DISPLAY INVISIBLE (-725 4050);
FORCEADD Q_CAP..1
R 2
(-775 3700);
FORCEPROP 1 LAST LOCATION C629
J 2
(-825 3800);
DISPLAY 0.978723 (-825 3800);
FORCEPROP 2 LAST $SEC 1
J 0
(-825 3900);
DISPLAY 0.680851 (-825 3900);
PAINT MONO (-825 3900);
DISPLAY INVISIBLE (-825 3900);
FORCEPROP 2 LAST CDS_SEC 1
J 0
(-825 3900);
DISPLAY 1.021277 (-825 3900);
DISPLAY INVISIBLE (-825 3900);
FORCEPROP 1 LASTPIN (-775 3800) $PN 1
J 2
(-785 3780);
DISPLAY 0.787234 (-785 3780);
FORCEPROP 1 LASTPIN (-775 3600) $PN 2
J 2
(-785 3580);
DISPLAY 0.787234 (-785 3580);
FORCEPROP 1 LAST PACK_TYPE 0402
J 2
(-825 3500);
DISPLAY 0.510638 (-825 3500);
FORCEPROP 1 LAST VALUE 0.1UF
J 2
(-825 3750);
DISPLAY 0.510638 (-825 3750);
FORCEPROP 1 LAST VOLTAGE 25V
J 2
(-825 3700);
DISPLAY 0.510638 (-825 3700);
FORCEPROP 1 LAST TOLERANCE 10%
J 2
(-825 3650);
DISPLAY 0.510638 (-825 3650);
FORCEPROP 1 LAST MATERIAL X7R
J 2
(-825 3600);
DISPLAY 0.510638 (-825 3600);
FORCEPROP 2 LAST CDS_LIB pure_quanta
J 0
(-775 3700);
PAINT MONO (-775 3700);
DISPLAY INVISIBLE (-775 3700);
FORCEPROP 1 LAST PATH I55
J 2
(-825 3850);
DISPLAY 0.978723 (-825 3850);
PAINT WHITE (-825 3850);
DISPLAY INVISIBLE (-825 3850);
FORCEPROP 1 LAST PART_NUMBER CH4104K1B00
J 2
(-825 3550);
DISPLAY 0.510638 (-825 3550);
DISPLAY INVISIBLE (-825 3550);
FORCEADD UNIVERSAL_GND..1
(-775 3475);
FORCEPROP 3 LASTPIN (-775 3525) SIG_NAME GND\g
J 0
(-765 3535);
DISPLAY 0.659574 (-765 3535);
PAINT MONO (-765 3535);
DISPLAY INVISIBLE (-765 3535);
FORCEPROP 2 LAST CDS_LIB pure_quanta_power
J 0
(-775 3475);
PAINT MONO (-775 3475);
DISPLAY INVISIBLE (-775 3475);
FORCEPROP 1 LAST HDL_POWER GND
J 1
(-750 3400);
DISPLAY 0.872340 (-750 3400);
PAINT GREEN (-750 3400);
DISPLAY INVISIBLE (-750 3400);
FORCEPROP 1 LAST PATH I56
J 0
(-700 3475);
DISPLAY 0.872340 (-700 3475);
PAINT AQUA (-700 3475);
DISPLAY INVISIBLE (-700 3475);
FORCEADD Q_RES..2
(-1325 3075);
FORCEPROP 1 LAST LOCATION R710
J 0
(-1280 3200);
DISPLAY 0.978723 (-1280 3200);
FORCEPROP 2 LAST $SEC 1
J 0
(-1275 3300);
DISPLAY 0.680851 (-1275 3300);
PAINT MONO (-1275 3300);
DISPLAY INVISIBLE (-1275 3300);
FORCEPROP 2 LAST CDS_SEC 1
J 0
(-1275 3300);
DISPLAY 1.021277 (-1275 3300);
DISPLAY INVISIBLE (-1275 3300);
FORCEPROP 1 LASTPIN (-1325 3175) $PN 1
J 0
(-1320 3137);
DISPLAY 0.787234 (-1320 3137);
FORCEPROP 1 LASTPIN (-1325 2975) $PN 2
J 0
(-1320 2985);
DISPLAY 0.787234 (-1320 2985);
FORCEPROP 1 LAST WATTAGE 1/16W
J 0
(-1285 3050);
DISPLAY 0.510638 (-1285 3050);
FORCEPROP 1 LAST PACK_TYPE 0402LF
J 0
(-1285 2900);
DISPLAY 0.510638 (-1285 2900);
FORCEPROP 1 LAST TOLERANCE 1%
J 0
(-1280 3100);
DISPLAY 0.510638 (-1280 3100);
FORCEPROP 1 LAST VALUE 1K
J 0
(-1280 3150);
DISPLAY 0.510638 (-1280 3150);
FORCEPROP 1 LAST MATERIAL CHIP
J 0
(-1285 3000);
DISPLAY 0.510638 (-1285 3000);
FORCEPROP 2 LAST CDS_LIB pure_quanta
J 0
(-1325 3075);
PAINT MONO (-1325 3075);
DISPLAY INVISIBLE (-1325 3075);
FORCEPROP 1 LAST PATH I57
J 0
(-1275 3250);
DISPLAY 0.978723 (-1275 3250);
PAINT WHITE (-1275 3250);
DISPLAY INVISIBLE (-1275 3250);
FORCEPROP 1 LAST PART_NUMBER CS21002FB06
J 0
(-1285 2950);
DISPLAY 0.510638 (-1285 2950);
DISPLAY INVISIBLE (-1285 2950);
FORCEADD UNIVERSAL_GND..1
(-1325 2850);
FORCEPROP 3 LASTPIN (-1325 2900) SIG_NAME GND\g
J 0
(-1315 2910);
DISPLAY 0.659574 (-1315 2910);
PAINT MONO (-1315 2910);
DISPLAY INVISIBLE (-1315 2910);
FORCEPROP 2 LAST CDS_LIB pure_quanta_power
J 0
(-1325 2850);
PAINT MONO (-1325 2850);
DISPLAY INVISIBLE (-1325 2850);
FORCEPROP 1 LAST HDL_POWER GND
J 1
(-1300 2775);
DISPLAY 0.872340 (-1300 2775);
PAINT GREEN (-1300 2775);
DISPLAY INVISIBLE (-1300 2775);
FORCEPROP 1 LAST PATH I58
J 0
(-1250 2850);
DISPLAY 0.872340 (-1250 2850);
PAINT AQUA (-1250 2850);
DISPLAY INVISIBLE (-1250 2850);
FORCEADD UNIVERSAL_GND..1
(200 3050);
FORCEPROP 3 LASTPIN (200 3100) SIG_NAME GND\g
J 0
(210 3110);
DISPLAY 0.659574 (210 3110);
PAINT MONO (210 3110);
DISPLAY INVISIBLE (210 3110);
FORCEPROP 2 LAST CDS_LIB pure_quanta_power
J 0
(200 3050);
PAINT MONO (200 3050);
DISPLAY INVISIBLE (200 3050);
FORCEPROP 1 LAST HDL_POWER GND
J 1
(225 2975);
DISPLAY 0.872340 (225 2975);
PAINT GREEN (225 2975);
DISPLAY INVISIBLE (225 2975);
FORCEPROP 1 LAST PATH I59
J 0
(275 3050);
DISPLAY 0.872340 (275 3050);
PAINT AQUA (275 3050);
DISPLAY INVISIBLE (275 3050);
FORCEADD UNIVERSAL_POWER..1
(1500 4050);
FORCEPROP 3 LASTPIN (1500 4000) SIG_NAME P3V3_AUX\g
J 0
(1510 4010);
DISPLAY 0.659574 (1510 4010);
PAINT MONO (1510 4010);
DISPLAY INVISIBLE (1510 4010);
FORCEPROP 1 LAST HDL_POWER P3V3_AUX
J 1
(1500 4100);
DISPLAY 0.872340 (1500 4100);
PAINT GREEN (1500 4100);
FORCEPROP 2 LAST CDS_LIB pure_quanta_power
J 0
(1500 4050);
PAINT MONO (1500 4050);
DISPLAY INVISIBLE (1500 4050);
FORCEPROP 1 LAST PATH I60
J 0
(1550 4075);
DISPLAY 0.872340 (1550 4075);
PAINT AQUA (1550 4075);
DISPLAY INVISIBLE (1550 4075);
FORCEADD Q_RES..2
(2050 3125);
FORCEPROP 1 LAST LOCATION R722
J 0
(2095 3250);
DISPLAY 0.978723 (2095 3250);
FORCEPROP 2 LAST $SEC 1
J 0
(2100 3350);
DISPLAY 0.680851 (2100 3350);
PAINT MONO (2100 3350);
DISPLAY INVISIBLE (2100 3350);
FORCEPROP 2 LAST CDS_SEC 1
J 0
(2100 3350);
DISPLAY 1.021277 (2100 3350);
DISPLAY INVISIBLE (2100 3350);
FORCEPROP 1 LASTPIN (2050 3225) $PN 1
J 0
(2055 3187);
DISPLAY 0.787234 (2055 3187);
FORCEPROP 1 LASTPIN (2050 3025) $PN 2
J 0
(2055 3035);
DISPLAY 0.787234 (2055 3035);
FORCEPROP 1 LAST WATTAGE 1/16W
J 0
(2090 3100);
DISPLAY 0.638298 (2090 3100);
FORCEPROP 1 LAST MATERIAL EMPTY
J 0
(2090 3050);
DISPLAY 0.638298 (2090 3050);
PAINT RED (2090 3050);
FORCEPROP 1 LAST PACK_TYPE 0402LF
J 0
(2090 3000);
DISPLAY 0.638298 (2090 3000);
FORCEPROP 1 LAST VALUE 1K
J 0
(2095 3200);
DISPLAY 0.638298 (2095 3200);
FORCEPROP 1 LAST TOLERANCE 1%
J 0
(2095 3150);
DISPLAY 0.638298 (2095 3150);
FORCEPROP 2 LAST CDS_LIB pure_quanta
J 0
(2050 3125);
PAINT MONO (2050 3125);
DISPLAY INVISIBLE (2050 3125);
FORCEPROP 1 LAST PATH I61
J 0
(2100 3300);
DISPLAY 0.978723 (2100 3300);
PAINT WHITE (2100 3300);
DISPLAY INVISIBLE (2100 3300);
FORCEPROP 1 LAST PART_NUMBER CS21002FB06
J 0
(2090 2950);
DISPLAY 0.638298 (2090 2950);
DISPLAY INVISIBLE (2090 2950);
FORCEADD Q_RES..2
(2050 3675);
FORCEPROP 1 LAST LOCATION R721
J 0
(2095 3800);
DISPLAY 0.978723 (2095 3800);
FORCEPROP 2 LAST $SEC 1
J 0
(2100 3900);
DISPLAY 0.680851 (2100 3900);
PAINT MONO (2100 3900);
DISPLAY INVISIBLE (2100 3900);
FORCEPROP 2 LAST CDS_SEC 1
J 0
(2100 3900);
DISPLAY 1.021277 (2100 3900);
DISPLAY INVISIBLE (2100 3900);
FORCEPROP 1 LASTPIN (2050 3775) $PN 1
J 0
(2055 3737);
DISPLAY 0.787234 (2055 3737);
FORCEPROP 1 LASTPIN (2050 3575) $PN 2
J 0
(2055 3585);
DISPLAY 0.787234 (2055 3585);
FORCEPROP 1 LAST VALUE 10K
J 0
(2095 3750);
DISPLAY 0.638298 (2095 3750);
FORCEPROP 1 LAST TOLERANCE 1%
J 0
(2095 3700);
DISPLAY 0.638298 (2095 3700);
FORCEPROP 1 LAST WATTAGE 1/16W
J 0
(2090 3650);
DISPLAY 0.638298 (2090 3650);
FORCEPROP 1 LAST MATERIAL CHIP
J 0
(2090 3600);
DISPLAY 0.638298 (2090 3600);
FORCEPROP 1 LAST PACK_TYPE 0402LF
J 0
(2090 3550);
DISPLAY 0.638298 (2090 3550);
FORCEPROP 2 LAST CDS_LIB pure_quanta
J 0
(2050 3675);
PAINT MONO (2050 3675);
DISPLAY INVISIBLE (2050 3675);
FORCEPROP 1 LAST PATH I62
J 0
(2100 3850);
DISPLAY 0.978723 (2100 3850);
PAINT WHITE (2100 3850);
DISPLAY INVISIBLE (2100 3850);
FORCEPROP 1 LAST PART_NUMBER CS31002FB08
J 0
(2090 3500);
DISPLAY 0.638298 (2090 3500);
DISPLAY INVISIBLE (2090 3500);
FORCEADD Q_RES..2
(-1925 3650);
FORCEPROP 1 LAST LOCATION R43
J 0
(-1880 3775);
DISPLAY 0.787234 (-1880 3775);
FORCEPROP 2 LAST $SEC 1
J 0
(-1875 3875);
DISPLAY 0.680851 (-1875 3875);
PAINT MONO (-1875 3875);
DISPLAY INVISIBLE (-1875 3875);
FORCEPROP 2 LAST CDS_SEC 1
J 0
(-1875 3875);
DISPLAY 1.021277 (-1875 3875);
DISPLAY INVISIBLE (-1875 3875);
FORCEPROP 1 LASTPIN (-1925 3750) $PN 1
J 0
(-1920 3712);
DISPLAY 0.787234 (-1920 3712);
FORCEPROP 1 LASTPIN (-1925 3550) $PN 2
J 0
(-1920 3560);
DISPLAY 0.787234 (-1920 3560);
FORCEPROP 1 LAST PACK_TYPE 0402LF
J 0
(-1885 3475);
DISPLAY 0.638298 (-1885 3475);
FORCEPROP 1 LAST VALUE 4.7K
J 0
(-1880 3725);
DISPLAY 0.638298 (-1880 3725);
FORCEPROP 1 LAST WATTAGE 1/16W
J 0
(-1885 3625);
DISPLAY 0.638298 (-1885 3625);
FORCEPROP 1 LAST TOLERANCE 5%
J 0
(-1880 3675);
DISPLAY 0.638298 (-1880 3675);
FORCEPROP 1 LAST MATERIAL EMPTY
J 0
(-1885 3575);
DISPLAY 0.638298 (-1885 3575);
PAINT RED (-1885 3575);
FORCEPROP 2 LAST CDS_LIB pure_quanta
J 0
(-1925 3650);
PAINT MONO (-1925 3650);
DISPLAY INVISIBLE (-1925 3650);
FORCEPROP 1 LAST PATH I93
J 0
(-1875 3825);
DISPLAY 0.978723 (-1875 3825);
PAINT WHITE (-1875 3825);
DISPLAY INVISIBLE (-1875 3825);
FORCEPROP 1 LAST PART_NUMBER CS24702JB10
J 0
(-1885 3525);
DISPLAY 0.638298 (-1885 3525);
DISPLAY INVISIBLE (-1885 3525);
FORCEADD Q_RES..2
R 2
(-2025 3650);
FORCEPROP 1 LAST LOCATION R26
J 2
(-2070 3775);
DISPLAY 0.787234 (-2070 3775);
FORCEPROP 2 LAST $SEC 1
J 0
(-2075 3875);
DISPLAY 0.680851 (-2075 3875);
PAINT MONO (-2075 3875);
DISPLAY INVISIBLE (-2075 3875);
FORCEPROP 2 LAST CDS_SEC 1
J 0
(-2075 3875);
DISPLAY 1.021277 (-2075 3875);
DISPLAY INVISIBLE (-2075 3875);
FORCEPROP 1 LASTPIN (-2025 3750) $PN 1
J 2
(-2030 3712);
DISPLAY 0.787234 (-2030 3712);
FORCEPROP 1 LASTPIN (-2025 3550) $PN 2
J 2
(-2030 3560);
DISPLAY 0.787234 (-2030 3560);
FORCEPROP 1 LAST PACK_TYPE 0402LF
J 2
(-2065 3475);
DISPLAY 0.638298 (-2065 3475);
FORCEPROP 1 LAST WATTAGE 1/16W
J 2
(-2065 3625);
DISPLAY 0.638298 (-2065 3625);
FORCEPROP 1 LAST MATERIAL EMPTY
J 2
(-2065 3575);
DISPLAY 0.638298 (-2065 3575);
PAINT RED (-2065 3575);
FORCEPROP 1 LAST VALUE 4.7K
J 2
(-2070 3725);
DISPLAY 0.638298 (-2070 3725);
FORCEPROP 1 LAST TOLERANCE 5%
J 2
(-2070 3675);
DISPLAY 0.638298 (-2070 3675);
FORCEPROP 2 LAST CDS_LIB pure_quanta
J 2
(-2025 3650);
PAINT MONO (-2025 3650);
DISPLAY INVISIBLE (-2025 3650);
FORCEPROP 1 LAST PATH I95
J 2
(-2075 3825);
DISPLAY 0.978723 (-2075 3825);
PAINT WHITE (-2075 3825);
DISPLAY INVISIBLE (-2075 3825);
FORCEPROP 1 LAST PART_NUMBER CS24702JB10
J 2
(-2065 3525);
DISPLAY 0.638298 (-2065 3525);
DISPLAY INVISIBLE (-2065 3525);
FORCEADD UNIVERSAL_POWER..1
(-2025 3950);
FORCEPROP 3 LASTPIN (-2025 3900) SIG_NAME P3V3_AUX\g
J 0
(-2015 3910);
DISPLAY 0.659574 (-2015 3910);
PAINT MONO (-2015 3910);
DISPLAY INVISIBLE (-2015 3910);
FORCEPROP 1 LAST HDL_POWER P3V3_AUX
J 1
(-2025 4000);
DISPLAY 0.872340 (-2025 4000);
PAINT GREEN (-2025 4000);
FORCEPROP 2 LAST CDS_LIB pure_quanta_power
J 0
(-2025 3950);
PAINT MONO (-2025 3950);
DISPLAY INVISIBLE (-2025 3950);
FORCEPROP 1 LAST PATH I96
J 0
(-1975 3975);
DISPLAY 0.872340 (-1975 3975);
PAINT AQUA (-1975 3975);
DISPLAY INVISIBLE (-1975 3975);
FORCEADD M24128BWMN6TP..1
(-225 1075);
FORCEPROP 1 LAST LOCATION U1
J 0
(-400 1400);
DISPLAY 0.723404 (-400 1400);
PAINT GREEN (-400 1400);
FORCEPROP 0 LAST $SEC 1
J 2
(-400 1650);
DISPLAY 0.680851 (-400 1650);
PAINT MONO (-400 1650);
DISPLAY INVISIBLE (-400 1650);
FORCEPROP 2 LAST CDS_SEC 1
J 0
(-375 1450);
DISPLAY 1.021277 (-375 1450);
DISPLAY INVISIBLE (-375 1450);
FORCEPROP 0 LASTPIN (75 1150) $PN 1
J 0
(85 1160);
DISPLAY 0.680851 (85 1160);
PAINT MONO (85 1160);
FORCEPROP 0 LASTPIN (75 1100) $PN 2
J 0
(85 1110);
DISPLAY 0.680851 (85 1110);
PAINT MONO (85 1110);
FORCEPROP 0 LASTPIN (75 1050) $PN 3
J 0
(85 1060);
DISPLAY 0.680851 (85 1060);
PAINT MONO (85 1060);
FORCEPROP 0 LASTPIN (-525 1050) $PN 6
J 2
(-535 1060);
DISPLAY 0.680851 (-535 1060);
PAINT MONO (-535 1060);
FORCEPROP 0 LASTPIN (-525 1000) $PN 5
J 2
(-535 1010);
DISPLAY 0.680851 (-535 1010);
PAINT MONO (-535 1010);
FORCEPROP 0 LASTPIN (-525 1150) $PN 8
J 2
(-535 1160);
DISPLAY 0.680851 (-535 1160);
PAINT MONO (-535 1160);
FORCEPROP 0 LASTPIN (75 1000) $PN 4
J 0
(85 1010);
DISPLAY 0.680851 (85 1010);
PAINT MONO (85 1010);
FORCEPROP 0 LASTPIN (-525 1100) $PN 7
J 2
(-535 1110);
DISPLAY 0.680851 (-535 1110);
PAINT MONO (-535 1110);
FORCEPROP 1 LAST MATERIAL IC
J 0
(-379 1216);
DISPLAY 0.723404 (-379 1216);
PAINT GREEN (-379 1216);
FORCEPROP 2 LAST PART_TYPE SMLF
J 0
(-400 1600);
DISPLAY 0.638298 (-400 1600);
FORCEPROP 2 LAST VALUE M24128-BWMN6TP
J 0
(-400 1525);
DISPLAY 0.638298 (-400 1525);
FORCEPROP 2 LAST CDS_LIB pure_quanta
J 2
(-225 1075);
DISPLAY INVISIBLE (-225 1075);
FORCEPROP 1 LAST NEEDS_NO_SIZE TRUE
J 0
(-225 1075);
DISPLAY 0.723404 (-225 1075);
PAINT GREEN (-225 1075);
DISPLAY INVISIBLE (-225 1075);
FORCEPROP 1 LAST CDS_LMAN_SYM_OUTLINE -150,125,150,-125
J 0
(-225 1075);
DISPLAY 0.468085 (-225 1075);
PAINT GREEN (-225 1075);
DISPLAY INVISIBLE (-225 1075);
FORCEPROP 1 LAST PATH I97
J 0
(-225 1075);
DISPLAY 0.723404 (-225 1075);
PAINT GREEN (-225 1075);
DISPLAY INVISIBLE (-225 1075);
FORCEPROP 1 LAST PART_NUMBER AKE30Z00613
J 0
(-375 1300);
DISPLAY 0.723404 (-375 1300);
PAINT GREEN (-375 1300);
DISPLAY INVISIBLE (-375 1300);
FORCEADD UNIVERSAL_GND..1
(2075 600);
FORCEPROP 3 LASTPIN (2075 650) SIG_NAME GND\g
J 0
(2085 660);
DISPLAY 0.659574 (2085 660);
PAINT MONO (2085 660);
DISPLAY INVISIBLE (2085 660);
FORCEPROP 2 LAST ROOM IO_SLOT
J 1
(1850 675);
DISPLAY 0.744681 (1850 675);
DISPLAY INVISIBLE (1850 675);
FORCEPROP 2 LAST CDS_LIB pure_quanta_power
J 0
(2075 600);
PAINT MONO (2075 600);
DISPLAY INVISIBLE (2075 600);
FORCEPROP 1 LAST HDL_POWER GND
J 1
(2100 525);
DISPLAY 0.872340 (2100 525);
PAINT GREEN (2100 525);
DISPLAY INVISIBLE (2100 525);
FORCEPROP 1 LAST PATH I98
J 0
(2150 600);
DISPLAY 0.872340 (2150 600);
PAINT AQUA (2150 600);
DISPLAY INVISIBLE (2150 600);
FORCEADD DNS..2
(1780 3645);
PAINT RED (1780 3645);
FORCEPROP 2 LAST CDS_LIB mstr_misc
J 0
(1780 3645);
PAINT MONO (1780 3645);
DISPLAY INVISIBLE (1780 3645);
FORCEPROP 1 LAST COMMENT_BODY TRUE
J 0
(1780 3645);
DISPLAY INVISIBLE (1780 3645);
FORCEADD DNS..2
(1505 3645);
PAINT RED (1505 3645);
FORCEPROP 2 LAST CDS_LIB mstr_misc
J 0
(1505 3645);
PAINT MONO (1505 3645);
DISPLAY INVISIBLE (1505 3645);
FORCEPROP 1 LAST COMMENT_BODY TRUE
J 0
(1505 3645);
DISPLAY INVISIBLE (1505 3645);
FORCEADD DNS..2
(2050 3100);
PAINT RED (2050 3100);
FORCEPROP 2 LAST CDS_LIB mstr_misc
J 0
(2050 3100);
PAINT MONO (2050 3100);
DISPLAY INVISIBLE (2050 3100);
FORCEPROP 1 LAST COMMENT_BODY TRUE
J 0
(2050 3100);
DISPLAY INVISIBLE (2050 3100);
FORCEADD DNS..2
(-1925 3625);
PAINT RED (-1925 3625);
FORCEPROP 2 LAST CDS_LIB mstr_misc
J 0
(-1925 3625);
DISPLAY INVISIBLE (-1925 3625);
FORCEPROP 1 LAST COMMENT_BODY TRUE
J 0
(-1925 3625);
DISPLAY INVISIBLE (-1925 3625);
FORCEADD DNS..2
(-2025 3625);
PAINT RED (-2025 3625);
FORCEPROP 2 LAST CDS_LIB mstr_misc
J 0
(-2025 3625);
DISPLAY INVISIBLE (-2025 3625);
FORCEPROP 1 LAST COMMENT_BODY TRUE
J 0
(-2025 3625);
DISPLAY INVISIBLE (-2025 3625);
FORCEADD DNS..2
(-2000 1325);
PAINT RED (-2000 1325);
FORCEPROP 2 LAST CDS_LIB mstr_misc
J 0
(-2000 1325);
DISPLAY INVISIBLE (-2000 1325);
FORCEPROP 1 LAST COMMENT_BODY TRUE
J 0
(-2000 1325);
DISPLAY INVISIBLE (-2000 1325);
FORCEADD DNS..2
(-1900 1325);
PAINT RED (-1900 1325);
FORCEPROP 2 LAST CDS_LIB mstr_misc
J 0
(-1900 1325);
DISPLAY INVISIBLE (-1900 1325);
FORCEPROP 1 LAST COMMENT_BODY TRUE
J 0
(-1900 1325);
DISPLAY INVISIBLE (-1900 1325);
FORCEADD DNS..2
(1530 1345);
PAINT RED (1530 1345);
FORCEPROP 2 LAST CDS_LIB mstr_misc
J 0
(1530 1345);
PAINT MONO (1530 1345);
DISPLAY INVISIBLE (1530 1345);
FORCEPROP 1 LAST COMMENT_BODY TRUE
J 0
(1530 1345);
DISPLAY INVISIBLE (1530 1345);
FORCEADD DNS..2
(1805 1345);
PAINT RED (1805 1345);
FORCEPROP 2 LAST CDS_LIB mstr_misc
J 0
(1805 1345);
PAINT MONO (1805 1345);
DISPLAY INVISIBLE (1805 1345);
FORCEPROP 1 LAST COMMENT_BODY TRUE
J 0
(1805 1345);
DISPLAY INVISIBLE (1805 1345);
FORCEADD DNS..2
(2125 1375);
PAINT RED (2125 1375);
FORCEPROP 2 LAST CDS_LIB mstr_misc
J 0
(2125 1375);
PAINT MONO (2125 1375);
DISPLAY INVISIBLE (2125 1375);
FORCEPROP 1 LAST COMMENT_BODY TRUE
J 0
(2125 1375);
DISPLAY INVISIBLE (2125 1375);
FORCEADD QUANTA_TITLE_BLOCK_C..1
(4700 -1475);
FORCEPROP 0 LAST CDS_CON_LAST_MODIFIED Thu Sep 14 16:12:31 2023
J 0
(2815 -1460);
PAINT MONO (2815 -1460);
DISPLAY INVISIBLE (2815 -1460);
FORCEPROP 1 LAST CUSTOM_TXT_CDS <CON_LAST_MODIFIED>
J 0
(2815 -1460);
DISPLAY 0.978723 (2815 -1460);
FORCEPROP 2 LAST CUSTOM_TXT_CDS <XR_PAGE_TITLE>
J 0
(-3190 3775);
DISPLAY 0.638298 (-3190 3775);
PAINT PINK (-3190 3775);
DISPLAY INVISIBLE (-3190 3775);
FORCEPROP 1 LAST CUSTOM_TXT_CDS <NAME_2>
J 0
(1525 -1425);
FORCEPROP 1 LAST CUSTOM_TXT_CDS <NAME_1>
J 0
(1525 -1300);
FORCEPROP 1 LAST CUSTOM_TXT_CDS <Q_NUMBER>
J 0
(3297 -1372);
DISPLAY 1.212766 (3297 -1372);
FORCEPROP 1 LAST CUSTOM_TXT_CDS <Q_PROJ>
J 0
(2318 -1373);
DISPLAY 1.212766 (2318 -1373);
FORCEPROP 1 LAST CUSTOM_TXT_CDS <Q_REV>
J 0
(4516 -1372);
DISPLAY 1.212766 (4516 -1372);
FORCEPROP 1 LAST CUSTOM_TXT_CDS <CON_PAGE_NUM> OF <CON_TOTAL_PAGES>
J 0
(4254 -1457);
DISPLAY 0.978723 (4254 -1457);
FORCEPROP 1 LAST Q_TITLE MB FRU
J 0
(-4566 -1474);
DISPLAY 2.446809 (-4566 -1474);
PAINT GREEN (-4566 -1474);
FORCEPROP 2 LAST PAGE_BORDER TRUE
J 0
(-3190 3775);
DISPLAY 0.638298 (-3190 3775);
PAINT PINK (-3190 3775);
DISPLAY INVISIBLE (-3190 3775);
FORCEPROP 1 LAST CDS_LMAN_SYM_OUTLINE -9475,6775,100,-125
J 0
(4700 -1475);
DISPLAY 0.468085 (4700 -1475);
PAINT GREEN (4700 -1475);
DISPLAY INVISIBLE (4700 -1475);
FORCEPROP 2 LAST CDS_LIB pure_quanta
J 0
(4700 -1475);
PAINT MONO (4700 -1475);
DISPLAY INVISIBLE (4700 -1475);
FORCEPROP 2 LAST CDS_XR_PAGE_TITLE CR-239 : @T6G_MB_LIB.T6G(SCH_1):PAGE239
J 0
(-3190 3775);
DISPLAY 0.638298 (-3190 3775);
PAINT PINK (-3190 3775);
DISPLAY INVISIBLE (-3190 3775);
FORCEPROP 1 LAST Q_DEPT BU9
J 1
(937 -1426);
DISPLAY 1.957447 (937 -1426);
PAINT GREEN (937 -1426);
DISPLAY INVISIBLE (937 -1426);
FORCEPROP 1 LAST COMMENT_BODY TRUE
J 0
(4712 -1488);
DISPLAY 0.978723 (4712 -1488);
PAINT GREEN (4712 -1488);
DISPLAY INVISIBLE (4712 -1488);
WIRE 16 -1 (1800 650)(1800 725);
WIRE 16 -1 (1525 650)(1525 725);
WIRE 16 -1 (-750 1300)(-750 1225);
WIRE 16 -1 (-1075 650)(-1075 575);
WIRE 16 -1 (2050 2950)(2050 3025);
WIRE 16 -1 (1775 2950)(1775 3025);
WIRE 16 -1 (1500 2950)(1500 3025);
WIRE 16 -1 (-775 3600)(-775 3525);
WIRE 16 -1 (-1325 2975)(-1325 2900);
WIRE 16 -1 (2075 650)(2075 725);
WIRE 16 -1 (-1925 3850)(-2025 3850);
WIRE 16 -1 (-1925 3750)(-1925 3850);
WIRE 16 -1 (-2025 3900)(-2025 3850);
WIRE 16 -1 (-2025 3850)(-2025 3750);
WIRE 16 -1 (1800 925)(1800 1100);
WIRE 16 -1 (1800 1100)(1800 1275);
WIRE 16 -1 (75 1100)(1800 1100);
FORCEPROP 0 LAST CDS_PHYS_NET_NAME PCA9548_PCIE_ADDR2
J 0
(815 1148);
PAINT MONO (815 1148);
DISPLAY INVISIBLE (815 1148);
FORCEPROP 2 LAST SIG_NAME CPU_FRU_ADDR1
J 0
(240 1110);
DISPLAY 0.808511 (240 1110);
PAINT WHITE (240 1110);
FORCEPROP 2 LASTPROP $XRERR UNIQUE?
J 0
(0 1110);
DISPLAY 0.638298 (0 1110);
PAINT MONO (0 1110);
DISPLAY INVISIBLE (0 1110);
WIRE 16 -1 (1800 1625)(2075 1625);
WIRE 16 -1 (1800 1475)(1800 1625);
WIRE 16 -1 (1525 1625)(1800 1625);
WIRE 16 -1 (2075 1475)(2075 1625);
WIRE 16 -1 (1525 1475)(1525 1625);
WIRE 16 -1 (1525 1625)(1525 1700);
WIRE 16 -1 (1775 3925)(2050 3925);
WIRE 16 -1 (1775 3775)(1775 3925);
WIRE 16 -1 (1500 3925)(1775 3925);
WIRE 16 -1 (2050 3775)(2050 3925);
WIRE 16 -1 (1500 3775)(1500 3925);
WIRE 16 -1 (1500 3925)(1500 4000);
WIRE 16 -1 (50 3300)(200 3300);
WIRE 16 -1 (200 3100)(200 3300);
WIRE 16 -1 (-775 3900)(-650 3900);
FORCEPROP 0 LAST VOLTAGE 3.3
J 0
(-712 3900);
PAINT MONO (-712 3900);
DISPLAY INVISIBLE (-712 3900);
FORCEPROP 0 LAST CDS_PHYS_NET_NAME P3V3_AUX
J 0
(-712 3947);
PAINT MONO (-712 3947);
DISPLAY INVISIBLE (-712 3947);
FORCEPROP 0 LAST $PHYS_NET_NAME P3V3_AUX
J 0
(-712 3994);
PAINT MONO (-712 3994);
DISPLAY INVISIBLE (-712 3994);
WIRE 16 -1 (-775 3975)(-775 3900);
WIRE 16 -1 (-775 3900)(-775 3800);
WIRE 16 -1 (-650 3450)(-650 3900);
FORCEPROP 0 LAST VOLTAGE 3.3
J 0
(-650 3675);
PAINT MONO (-650 3675);
DISPLAY INVISIBLE (-650 3675);
FORCEPROP 0 LAST CDS_PHYS_NET_NAME P3V3_AUX
J 0
(-650 3722);
PAINT MONO (-650 3722);
DISPLAY INVISIBLE (-650 3722);
FORCEPROP 0 LAST $PHYS_NET_NAME P3V3_AUX
J 0
(-650 3769);
PAINT MONO (-650 3769);
DISPLAY INVISIBLE (-650 3769);
WIRE 16 -1 (-650 3450)(-550 3450);
FORCEPROP 0 LAST VOLTAGE 3.3
J 0
(-600 3450);
PAINT MONO (-600 3450);
DISPLAY INVISIBLE (-600 3450);
FORCEPROP 0 LAST CDS_PHYS_NET_NAME P3V3_AUX
J 0
(-600 3497);
PAINT MONO (-600 3497);
DISPLAY INVISIBLE (-600 3497);
FORCEPROP 0 LAST $PHYS_NET_NAME P3V3_AUX
J 0
(-600 3544);
PAINT MONO (-600 3544);
DISPLAY INVISIBLE (-600 3544);
WIRE 16 -1 (-1900 1550)(-2000 1550);
WIRE 16 -1 (-1900 1450)(-1900 1550);
WIRE 16 -1 (-2000 1600)(-2000 1550);
WIRE 16 -1 (-2000 1550)(-2000 1450);
WIRE 16 -1 (-750 1600)(-625 1600);
FORCEPROP 0 LAST VOLTAGE 3.3
J 0
(-687 1600);
PAINT MONO (-687 1600);
DISPLAY INVISIBLE (-687 1600);
FORCEPROP 0 LAST CDS_PHYS_NET_NAME P3V3_AUX
J 0
(-687 1647);
PAINT MONO (-687 1647);
DISPLAY INVISIBLE (-687 1647);
FORCEPROP 0 LAST $PHYS_NET_NAME P3V3_AUX
J 0
(-687 1694);
PAINT MONO (-687 1694);
DISPLAY INVISIBLE (-687 1694);
WIRE 16 -1 (-750 1675)(-750 1600);
WIRE 16 -1 (-750 1600)(-750 1500);
WIRE 16 -1 (-625 1150)(-625 1600);
FORCEPROP 0 LAST VOLTAGE 3.3
J 0
(-625 1375);
PAINT MONO (-625 1375);
DISPLAY INVISIBLE (-625 1375);
FORCEPROP 0 LAST CDS_PHYS_NET_NAME P3V3_AUX
J 0
(-625 1422);
PAINT MONO (-625 1422);
DISPLAY INVISIBLE (-625 1422);
FORCEPROP 0 LAST $PHYS_NET_NAME P3V3_AUX
J 0
(-625 1469);
PAINT MONO (-625 1469);
DISPLAY INVISIBLE (-625 1469);
WIRE 16 -1 (-625 1150)(-525 1150);
FORCEPROP 0 LAST VOLTAGE 3.3
J 0
(-575 1150);
PAINT MONO (-575 1150);
DISPLAY INVISIBLE (-575 1150);
FORCEPROP 0 LAST CDS_PHYS_NET_NAME P3V3_AUX
J 0
(-575 1197);
PAINT MONO (-575 1197);
DISPLAY INVISIBLE (-575 1197);
FORCEPROP 0 LAST $PHYS_NET_NAME P3V3_AUX
J 0
(-575 1244);
PAINT MONO (-575 1244);
DISPLAY INVISIBLE (-575 1244);
WIRE 16 -1 (75 1000)(225 1000);
WIRE 16 -1 (225 800)(225 1000);
WIRE 16 -1 (2075 1150)(2075 1275);
WIRE 16 -1 (2075 925)(2075 1150);
WIRE 16 -1 (2075 1150)(75 1150);
FORCEPROP 0 LAST CDS_PHYS_NET_NAME PCA9548_PCIE_ADDR2
J 0
(815 1198);
PAINT MONO (815 1198);
DISPLAY INVISIBLE (815 1198);
FORCEPROP 2 LAST SIG_NAME CPU_FRU_ADDR0
J 0
(240 1160);
DISPLAY 0.808511 (240 1160);
PAINT WHITE (240 1160);
FORCEPROP 2 LASTPROP $XRERR UNIQUE?
J 0
(0 1160);
DISPLAY 0.638298 (0 1160);
PAINT MONO (0 1160);
DISPLAY INVISIBLE (0 1160);
WIRE 16 -1 (-1325 3175)(-1325 3400);
WIRE 16 -1 (-550 3400)(-1325 3400);
FORCEPROP 2 LAST SIG_NAME PD_MB_FRU_WP
J 0
(-1185 3410);
DISPLAY 0.510638 (-1185 3410);
PAINT WHITE (-1185 3410);
FORCEPROP 2 LASTPROP $XRERR UNIQUE?
J 0
(-1425 3410);
DISPLAY 0.638298 (-1425 3410);
PAINT MONO (-1425 3410);
DISPLAY INVISIBLE (-1425 3410);
WIRE 16 -1 (-1925 3550)(-1925 3300);
WIRE 16 -1 (-1925 3300)(-550 3300);
FORCEPROP 0 LAST CDS_PHYS_NET_NAME SMB_PCIE_3V3AUX_SDA_R
J 0
(-1135 3348);
PAINT MONO (-1135 3348);
DISPLAY INVISIBLE (-1135 3348);
FORCEPROP 2 LAST SIG_NAME SMB_FRU_3V3AUX_R1_SDA
J 0
(-1210 3310);
DISPLAY 0.510638 (-1210 3310);
PAINT WHITE (-1210 3310);
FORCEPROP 2 LASTPROP $XRERR UNIQUE?
J 0
(-1450 3310);
DISPLAY 0.638298 (-1450 3310);
PAINT MONO (-1450 3310);
DISPLAY INVISIBLE (-1450 3310);
WIRE 16 -1 (-2275 3300)(-1925 3300);
FORCEPROP 0 LAST CDS_PHYS_NET_NAME SMB_PCIE_3V3AUX_SCL
J 0
(-2235 3348);
PAINT MONO (-2235 3348);
DISPLAY INVISIBLE (-2235 3348);
WIRE 16 -1 (2050 3450)(2050 3575);
WIRE 16 -1 (2050 3225)(2050 3450);
WIRE 16 -1 (2050 3450)(50 3450);
FORCEPROP 0 LAST CDS_PHYS_NET_NAME PCA9548_PCIE_ADDR2
J 0
(790 3498);
PAINT MONO (790 3498);
DISPLAY INVISIBLE (790 3498);
FORCEPROP 2 LAST SIG_NAME MB_FRU_ADDR0
J 0
(215 3460);
DISPLAY 0.808511 (215 3460);
PAINT WHITE (215 3460);
FORCEPROP 2 LASTPROP $XRERR UNIQUE?
J 0
(-25 3460);
DISPLAY 0.638298 (-25 3460);
PAINT MONO (-25 3460);
DISPLAY INVISIBLE (-25 3460);
WIRE 16 -1 (1500 3575)(1500 3350);
WIRE 16 -1 (1500 3350)(1500 3225);
WIRE 16 -1 (50 3350)(1500 3350);
FORCEPROP 0 LAST CDS_PHYS_NET_NAME PCA9548_PCIE_ADDR2
J 0
(790 3398);
PAINT MONO (790 3398);
DISPLAY INVISIBLE (790 3398);
FORCEPROP 2 LAST SIG_NAME MB_FRU_ADDR2
J 0
(215 3360);
DISPLAY 0.808511 (215 3360);
PAINT WHITE (215 3360);
FORCEPROP 2 LASTPROP $XRERR UNIQUE?
J 0
(-25 3360);
DISPLAY 0.638298 (-25 3360);
PAINT MONO (-25 3360);
DISPLAY INVISIBLE (-25 3360);
WIRE 16 -1 (1775 3225)(1775 3400);
WIRE 16 -1 (1775 3400)(1775 3575);
WIRE 16 -1 (50 3400)(1775 3400);
FORCEPROP 0 LAST CDS_PHYS_NET_NAME PCA9548_PCIE_ADDR2
J 0
(790 3448);
PAINT MONO (790 3448);
DISPLAY INVISIBLE (790 3448);
FORCEPROP 2 LAST SIG_NAME MB_FRU_ADDR1
J 0
(215 3410);
DISPLAY 0.808511 (215 3410);
PAINT WHITE (215 3410);
FORCEPROP 2 LASTPROP $XRERR UNIQUE?
J 0
(-25 3410);
DISPLAY 0.638298 (-25 3410);
PAINT MONO (-25 3410);
DISPLAY INVISIBLE (-25 3410);
WIRE 16 -1 (-2025 3550)(-2025 3350);
WIRE 16 -1 (-2025 3350)(-550 3350);
FORCEPROP 0 LAST CDS_PHYS_NET_NAME SMB_PCIE_3V3AUX_SCL_R
J 0
(-1135 3398);
PAINT MONO (-1135 3398);
DISPLAY INVISIBLE (-1135 3398);
FORCEPROP 2 LAST SIG_NAME SMB_FRU_3V3AUX_R1_SCL
J 0
(-1210 3360);
DISPLAY 0.510638 (-1210 3360);
PAINT WHITE (-1210 3360);
FORCEPROP 2 LASTPROP $XRERR UNIQUE?
J 0
(-1450 3360);
DISPLAY 0.638298 (-1450 3360);
PAINT MONO (-1450 3360);
DISPLAY INVISIBLE (-1450 3360);
WIRE 16 -1 (-2275 3350)(-2025 3350);
FORCEPROP 0 LAST CDS_PHYS_NET_NAME SMB_PCIE_3V3AUX_SDA
J 0
(-2060 3398);
PAINT MONO (-2060 3398);
DISPLAY INVISIBLE (-2060 3398);
WIRE 16 -1 (-1900 1250)(-1900 1000);
WIRE 16 -1 (-1900 1000)(-525 1000);
FORCEPROP 0 LAST CDS_PHYS_NET_NAME SMB_PCIE_3V3AUX_SDA_R
J 0
(-1110 1048);
PAINT MONO (-1110 1048);
DISPLAY INVISIBLE (-1110 1048);
FORCEPROP 2 LAST SIG_NAME SMB_CPU_FRU_3V3AUX_SDA
J 0
(-1810 1010);
DISPLAY 0.510638 (-1810 1010);
PAINT WHITE (-1810 1010);
FORCEPROP 2 LASTPROP $XRERR UNIQUE?
J 0
(-2050 1010);
DISPLAY 0.638298 (-2050 1010);
PAINT MONO (-2050 1010);
DISPLAY INVISIBLE (-2050 1010);
WIRE 16 -1 (-2225 1000)(-1900 1000);
FORCEPROP 0 LAST CDS_PHYS_NET_NAME SMB_PCIE_3V3AUX_SCL
J 0
(-2185 1048);
PAINT MONO (-2185 1048);
DISPLAY INVISIBLE (-2185 1048);
WIRE 16 -1 (1525 1275)(1525 1050);
WIRE 16 -1 (1525 1050)(1525 925);
WIRE 16 -1 (75 1050)(1525 1050);
FORCEPROP 0 LAST CDS_PHYS_NET_NAME PCA9548_PCIE_ADDR2
J 0
(815 1098);
PAINT MONO (815 1098);
DISPLAY INVISIBLE (815 1098);
FORCEPROP 2 LAST SIG_NAME CPU_FRU_ADDR2
J 0
(240 1060);
DISPLAY 0.808511 (240 1060);
PAINT WHITE (240 1060);
FORCEPROP 2 LASTPROP $XRERR UNIQUE?
J 0
(0 1060);
DISPLAY 0.638298 (0 1060);
PAINT MONO (0 1060);
DISPLAY INVISIBLE (0 1060);
WIRE 16 -1 (-2225 1050)(-2000 1050);
FORCEPROP 0 LAST CDS_PHYS_NET_NAME SMB_PCIE_3V3AUX_SDA
J 0
(-2035 1098);
PAINT MONO (-2035 1098);
DISPLAY INVISIBLE (-2035 1098);
WIRE 16 -1 (-2000 1050)(-525 1050);
FORCEPROP 0 LAST CDS_PHYS_NET_NAME SMB_PCIE_3V3AUX_SCL_R
J 0
(-1110 1098);
PAINT MONO (-1110 1098);
DISPLAY INVISIBLE (-1110 1098);
FORCEPROP 2 LAST SIG_NAME SMB_CPU_FRU_3V3AUX_SCL
J 0
(-1810 1060);
DISPLAY 0.510638 (-1810 1060);
PAINT WHITE (-1810 1060);
FORCEPROP 2 LASTPROP $XRERR UNIQUE?
J 0
(-2050 1060);
DISPLAY 0.638298 (-2050 1060);
PAINT MONO (-2050 1060);
DISPLAY INVISIBLE (-2050 1060);
WIRE 16 -1 (-2000 1250)(-2000 1050);
WIRE 16 -1 (-2425 1050)(-3100 1050);
FORCEPROP 2 LAST SIG_NAME SMB_FRU_3V3AUX_SCL
J 0
(-3085 1060);
DISPLAY 0.510638 (-3085 1060);
PAINT WHITE (-3085 1060);
WIRE 16 -1 (-1075 850)(-1075 1100);
WIRE 16 -1 (-525 1100)(-1075 1100);
FORCEPROP 2 LAST SIG_NAME PD_CPU_FRU_WP
J 0
(-935 1110);
DISPLAY 0.510638 (-935 1110);
PAINT WHITE (-935 1110);
FORCEPROP 2 LASTPROP $XRERR UNIQUE?
J 0
(-1175 1110);
DISPLAY 0.638298 (-1175 1110);
PAINT MONO (-1175 1110);
DISPLAY INVISIBLE (-1175 1110);
WIRE 16 -1 (-2475 3350)(-3300 3350);
FORCEPROP 2 LAST SIG_NAME SMB_FRU_3V3AUX_SCL
J 0
(-3235 3360);
DISPLAY 0.510638 (-3235 3360);
PAINT WHITE (-3235 3360);
WIRE 16 -1 (-3300 3300)(-2475 3300);
FORCEPROP 2 LAST SIG_NAME SMB_FRU_3V3AUX_SDA
J 0
(-3235 3310);
DISPLAY 0.510638 (-3235 3310);
PAINT WHITE (-3235 3310);
WIRE 16 -1 (-2425 1000)(-3100 1000);
FORCEPROP 2 LAST SIG_NAME SMB_FRU_3V3AUX_SDA
J 0
(-3085 1010);
DISPLAY 0.510638 (-3085 1010);
PAINT WHITE (-3085 1010);
CIRCLE (-3125 1750)(-2965 1750);
PAINT YELLOW (-3125 1750);
DOT 1 (-2000 1550);
DOT 1 (-2025 3350);
DOT 1 (-2000 1050);
DOT 1 (-1900 1000);
DOT 1 (-1925 3300);
DOT 1 (1800 1100);
DOT 1 (1800 1625);
DOT 1 (2075 1150);
DOT 1 (1525 1625);
DOT 1 (-750 1600);
DOT 1 (-2025 3850);
DOT 1 (-775 3900);
DOT 1 (1500 3350);
DOT 1 (1500 3925);
DOT 1 (1775 3400);
DOT 1 (1775 3925);
DOT 1 (2050 3450);
DOT 1 (1525 1050);
FORCENOTE
FRU ADDR: 0XA0 (8-BIT) / 0X50 (7-BIT)
(450 350) 0;
DISPLAY LEFT (450 350);
DISPLAY 1.595745 (450 350);
PAINT SKYBLUE (450 350);
FORCENOTE
CPU FRU EEPROM
(-625 575) 0;
DISPLAY LEFT (-625 575);
DISPLAY 1.595745 (-625 575);
FORCENOTE
FRU ADDR: 0XA2 (8-BIT) / 0X51 (7-BIT)
(425 2625) 0;
DISPLAY LEFT (425 2625);
DISPLAY 1.595745 (425 2625);
PAINT SKYBLUE (425 2625);
FORCENOTE
FRU EEPROM
(-650 2875) 0;
DISPLAY LEFT (-650 2875);
DISPLAY 1.595745 (-650 2875);
FORCENOTE
TBC
(-3200 1725) 0;
DISPLAY LEFT (-3200 1725);
DISPLAY 1.276596 (-3200 1725);
QUIT
